FILE_TYPE = MACRO_DRAWING;
SET COLOR_WIRE YELLOW;
SET COLOR_PROP MONO;
SET COLOR_DOT WHITE;
SET COLOR_ARC YELLOW;
SET COLOR_BODY GREEN;
SET COLOR_NOTE MONO;
SET PROP_DISPLAY VALUE;
SET PAGE_NUMBER P74;
FORCEADD GND..1
(-7625 475);
FORCEPROP 3 LASTPIN (-7625 525) SIG_NAME GND\g
J 0
(-7615 535);
DISPLAY 0.659574 (-7615 535);
PAINT MONO (-7615 535);
DISPLAY INVISIBLE (-7615 535);
FORCEPROP 1 LAST VOLTAGE 0.0V
J 0
(-7670 432);
DISPLAY 0.340426 (-7670 432);
PAINT SKYBLUE (-7670 432);
DISPLAY INVISIBLE (-7670 432);
FORCEPROP 1 LAST SIZE 1B
J 0
(-7550 425);
DISPLAY 1.170213 (-7550 425);
PAINT AQUA (-7550 425);
DISPLAY INVISIBLE (-7550 425);
FORCEPROP 2 LAST CDS_LIB mstr_symbols
J 0
(-7625 475);
PAINT ORANGE (-7625 475);
DISPLAY INVISIBLE (-7625 475);
FORCEPROP 1 LAST BODY_TYPE PLUMBING
J 0
(-7670 432);
DISPLAY 0.340426 (-7670 432);
PAINT GREEN (-7670 432);
DISPLAY INVISIBLE (-7670 432);
FORCEPROP 1 LAST PATH I1
J 0
(-7550 475);
DISPLAY 1.170213 (-7550 475);
PAINT AQUA (-7550 475);
DISPLAY INVISIBLE (-7550 475);
FORCEPROP 1 LAST HDL_POWER GND
J 0
(-7625 625);
DISPLAY 1.170213 (-7625 625);
PAINT GREEN (-7625 625);
DISPLAY INVISIBLE (-7625 625);
FORCEADD GND..1
(-2425 500);
FORCEPROP 3 LASTPIN (-2425 550) SIG_NAME GND\g
J 0
(-2415 560);
DISPLAY 0.659574 (-2415 560);
PAINT MONO (-2415 560);
DISPLAY INVISIBLE (-2415 560);
FORCEPROP 1 LAST VOLTAGE 0.0V
J 0
(-2470 457);
DISPLAY 0.340426 (-2470 457);
PAINT SKYBLUE (-2470 457);
DISPLAY INVISIBLE (-2470 457);
FORCEPROP 2 LAST CDS_LIB mstr_symbols
J 0
(-2425 500);
PAINT ORANGE (-2425 500);
DISPLAY INVISIBLE (-2425 500);
FORCEPROP 1 LAST SIZE 1B
J 0
(-2350 450);
DISPLAY 1.170213 (-2350 450);
PAINT AQUA (-2350 450);
DISPLAY INVISIBLE (-2350 450);
FORCEPROP 1 LAST BODY_TYPE PLUMBING
J 0
(-2470 457);
DISPLAY 0.340426 (-2470 457);
PAINT GREEN (-2470 457);
DISPLAY INVISIBLE (-2470 457);
FORCEPROP 1 LAST PATH I11
J 0
(-2350 500);
DISPLAY 0.872340 (-2350 500);
PAINT AQUA (-2350 500);
DISPLAY INVISIBLE (-2350 500);
FORCEPROP 1 LAST HDL_POWER GND
J 0
(-2425 650);
DISPLAY 1.170213 (-2425 650);
PAINT GREEN (-2425 650);
DISPLAY INVISIBLE (-2425 650);
FORCEADD GND..1
(-2025 475);
FORCEPROP 3 LASTPIN (-2025 525) SIG_NAME GND\g
J 0
(-2015 535);
DISPLAY 0.659574 (-2015 535);
PAINT MONO (-2015 535);
DISPLAY INVISIBLE (-2015 535);
FORCEPROP 1 LAST VOLTAGE 0.0V
J 0
(-2070 432);
DISPLAY 0.340426 (-2070 432);
PAINT SKYBLUE (-2070 432);
DISPLAY INVISIBLE (-2070 432);
FORCEPROP 1 LAST SIZE 1B
J 0
(-1950 425);
DISPLAY 1.170213 (-1950 425);
PAINT AQUA (-1950 425);
DISPLAY INVISIBLE (-1950 425);
FORCEPROP 2 LAST CDS_LIB mstr_symbols
J 0
(-2025 475);
PAINT ORANGE (-2025 475);
DISPLAY INVISIBLE (-2025 475);
FORCEPROP 1 LAST BODY_TYPE PLUMBING
J 0
(-2070 432);
DISPLAY 0.340426 (-2070 432);
PAINT GREEN (-2070 432);
DISPLAY INVISIBLE (-2070 432);
FORCEPROP 1 LAST PATH I12
J 0
(-1950 475);
DISPLAY 0.872340 (-1950 475);
PAINT AQUA (-1950 475);
DISPLAY INVISIBLE (-1950 475);
FORCEPROP 1 LAST HDL_POWER GND
J 0
(-2025 625);
DISPLAY 1.170213 (-2025 625);
PAINT GREEN (-2025 625);
DISPLAY INVISIBLE (-2025 625);
FORCEADD GND..1
(-500 475);
FORCEPROP 3 LASTPIN (-500 525) SIG_NAME GND\g
J 0
(-490 535);
DISPLAY 0.659574 (-490 535);
PAINT MONO (-490 535);
DISPLAY INVISIBLE (-490 535);
FORCEPROP 1 LAST VOLTAGE 0.0V
J 0
(-545 432);
DISPLAY 0.340426 (-545 432);
PAINT SKYBLUE (-545 432);
DISPLAY INVISIBLE (-545 432);
FORCEPROP 1 LAST SIZE 1B
J 0
(-425 425);
DISPLAY 1.170213 (-425 425);
PAINT AQUA (-425 425);
DISPLAY INVISIBLE (-425 425);
FORCEPROP 2 LAST CDS_LIB mstr_symbols
J 0
(-500 475);
PAINT ORANGE (-500 475);
DISPLAY INVISIBLE (-500 475);
FORCEPROP 1 LAST BODY_TYPE PLUMBING
J 0
(-545 432);
DISPLAY 0.340426 (-545 432);
PAINT GREEN (-545 432);
DISPLAY INVISIBLE (-545 432);
FORCEPROP 1 LAST PATH I14
J 0
(-425 475);
DISPLAY 0.872340 (-425 475);
PAINT AQUA (-425 475);
DISPLAY INVISIBLE (-425 475);
FORCEPROP 1 LAST HDL_POWER GND
J 0
(-500 625);
DISPLAY 1.170213 (-500 625);
PAINT GREEN (-500 625);
DISPLAY INVISIBLE (-500 625);
FORCEADD SKX_EXT_B..23
(-6875 2600);
FORCEPROP 1 LAST LOCATION U2D1
J 0
(-7425 4850);
DISPLAY 0.617021 (-7425 4850);
PAINT AQUA (-7425 4850);
FORCEPROP 1 LAST PART_NUMBER TBD
J 0
(-7425 450);
DISPLAY 0.617021 (-7425 450);
PAINT BLUE (-7425 450);
FORCEPROP 1 LAST MATERIAL IC
J 0
(-7425 4800);
DISPLAY 0.617021 (-7425 4800);
PAINT SKYBLUE (-7425 4800);
FORCEPROP 2 LASTPIN (-7475 4550) $PN A42
J 2
(-7485 4560);
DISPLAY 0.617021 (-7485 4560);
PAINT ORANGE (-7485 4560);
FORCEPROP 2 LASTPIN (-7475 4500) $PN B43
J 2
(-7485 4510);
DISPLAY 0.617021 (-7485 4510);
PAINT ORANGE (-7485 4510);
FORCEPROP 2 LASTPIN (-7475 4450) $PN B5
J 2
(-7485 4460);
DISPLAY 0.617021 (-7485 4460);
PAINT ORANGE (-7485 4460);
FORCEPROP 2 LASTPIN (-7475 4400) $PN B79
J 2
(-7485 4410);
DISPLAY 0.617021 (-7485 4410);
PAINT ORANGE (-7485 4410);
FORCEPROP 2 LASTPIN (-7475 4350) $PN C4
J 2
(-7485 4360);
DISPLAY 0.617021 (-7485 4360);
PAINT ORANGE (-7485 4360);
FORCEPROP 2 LASTPIN (-7475 4300) $PN C80
J 2
(-7485 4310);
DISPLAY 0.617021 (-7485 4310);
PAINT ORANGE (-7485 4310);
FORCEPROP 2 LASTPIN (-7475 4250) $PN D3
J 2
(-7485 4260);
DISPLAY 0.617021 (-7485 4260);
PAINT ORANGE (-7485 4260);
FORCEPROP 2 LASTPIN (-7475 4200) $PN D81
J 2
(-7485 4210);
DISPLAY 0.617021 (-7485 4210);
PAINT ORANGE (-7485 4210);
FORCEPROP 2 LASTPIN (-7475 4150) $PN E82
J 2
(-7485 4160);
DISPLAY 0.617021 (-7485 4160);
PAINT ORANGE (-7485 4160);
FORCEPROP 2 LASTPIN (-7475 4100) $PN J86
J 2
(-7485 4110);
DISPLAY 0.617021 (-7485 4110);
PAINT ORANGE (-7485 4110);
FORCEPROP 2 LASTPIN (-7475 4050) $PN DY85
J 2
(-7485 4060);
DISPLAY 0.617021 (-7485 4060);
PAINT ORANGE (-7485 4060);
FORCEPROP 2 LASTPIN (-7475 4000) $PN EA84
J 2
(-7485 4010);
DISPLAY 0.617021 (-7485 4010);
PAINT ORANGE (-7485 4010);
FORCEPROP 2 LASTPIN (-7475 3950) $PN EB83
J 2
(-7485 3960);
DISPLAY 0.617021 (-7485 3960);
PAINT ORANGE (-7485 3960);
FORCEPROP 2 LASTPIN (-7475 3900) $PN DW2
J 2
(-7485 3910);
DISPLAY 0.617021 (-7485 3910);
PAINT ORANGE (-7485 3910);
FORCEPROP 2 LASTPIN (-7475 3850) $PN EC42
J 2
(-7485 3860);
DISPLAY 0.617021 (-7485 3860);
PAINT ORANGE (-7485 3860);
FORCEPROP 2 LASTPIN (-7475 3800) $PN EC6
J 2
(-7485 3810);
DISPLAY 0.617021 (-7485 3810);
PAINT ORANGE (-7485 3810);
FORCEPROP 2 LASTPIN (-7475 3750) $PN EC82
J 2
(-7485 3760);
DISPLAY 0.617021 (-7485 3760);
PAINT ORANGE (-7485 3760);
FORCEPROP 2 LASTPIN (-7475 3700) $PN ED41
J 2
(-7485 3710);
DISPLAY 0.617021 (-7485 3710);
PAINT ORANGE (-7485 3710);
FORCEPROP 2 LASTPIN (-7475 3650) $PN ED7
J 2
(-7485 3660);
DISPLAY 0.617021 (-7485 3660);
PAINT ORANGE (-7485 3660);
FORCEPROP 2 LASTPIN (-7475 3600) $PN ED81
J 2
(-7485 3610);
DISPLAY 0.617021 (-7485 3610);
PAINT ORANGE (-7485 3610);
FORCEPROP 2 LASTPIN (-7475 3550) $PN EE40
J 2
(-7485 3560);
DISPLAY 0.617021 (-7485 3560);
PAINT ORANGE (-7485 3560);
FORCEPROP 2 LASTPIN (-7475 3500) $PN EE8
J 2
(-7485 3510);
DISPLAY 0.617021 (-7485 3510);
PAINT ORANGE (-7485 3510);
FORCEPROP 2 LASTPIN (-7475 3450) $PN EE80
J 2
(-7485 3460);
DISPLAY 0.617021 (-7485 3460);
PAINT ORANGE (-7485 3460);
FORCEPROP 2 LASTPIN (-7475 3400) $PN ED69
J 2
(-7485 3410);
DISPLAY 0.617021 (-7485 3410);
PAINT ORANGE (-7485 3410);
FORCEPROP 2 LASTPIN (-7475 3350) $PN E66
J 2
(-7485 3360);
DISPLAY 0.617021 (-7485 3360);
PAINT ORANGE (-7485 3360);
FORCEPROP 2 LASTPIN (-7475 3300) $PN V11
J 2
(-7485 3310);
DISPLAY 0.617021 (-7485 3310);
PAINT ORANGE (-7485 3310);
FORCEPROP 2 LASTPIN (-7475 3250) $PN L8
J 2
(-7485 3260);
DISPLAY 0.617021 (-7485 3260);
PAINT ORANGE (-7485 3260);
FORCEPROP 2 LASTPIN (-7475 3200) $PN EA14
J 2
(-7485 3210);
DISPLAY 0.617021 (-7485 3210);
PAINT ORANGE (-7485 3210);
FORCEPROP 2 LASTPIN (-7475 3150) $PN DY63
J 2
(-7485 3160);
DISPLAY 0.617021 (-7485 3160);
PAINT ORANGE (-7485 3160);
FORCEPROP 2 LASTPIN (-7475 3100) $PN DY61
J 2
(-7485 3110);
DISPLAY 0.617021 (-7485 3110);
PAINT ORANGE (-7485 3110);
FORCEPROP 2 LASTPIN (-7475 3050) $PN DY59
J 2
(-7485 3060);
DISPLAY 0.617021 (-7485 3060);
PAINT ORANGE (-7485 3060);
FORCEPROP 2 LASTPIN (-7475 3000) $PN DY57
J 2
(-7485 3010);
DISPLAY 0.617021 (-7485 3010);
PAINT ORANGE (-7485 3010);
FORCEPROP 2 LASTPIN (-7475 2950) $PN DY55
J 2
(-7485 2960);
DISPLAY 0.617021 (-7485 2960);
PAINT ORANGE (-7485 2960);
FORCEPROP 2 LASTPIN (-7475 2900) $PN DY53
J 2
(-7485 2910);
DISPLAY 0.617021 (-7485 2910);
PAINT ORANGE (-7485 2910);
FORCEPROP 2 LASTPIN (-7475 2850) $PN DY51
J 2
(-7485 2860);
DISPLAY 0.617021 (-7485 2860);
PAINT ORANGE (-7485 2860);
FORCEPROP 2 LASTPIN (-7475 2800) $PN DY49
J 2
(-7485 2810);
DISPLAY 0.617021 (-7485 2810);
PAINT ORANGE (-7485 2810);
FORCEPROP 2 LASTPIN (-7475 2750) $PN DY47
J 2
(-7485 2760);
DISPLAY 0.617021 (-7485 2760);
PAINT ORANGE (-7485 2760);
FORCEPROP 2 LASTPIN (-7475 2700) $PN DY45
J 2
(-7485 2710);
DISPLAY 0.617021 (-7485 2710);
PAINT ORANGE (-7485 2710);
FORCEPROP 2 LASTPIN (-7475 2650) $PN DV19
J 2
(-7485 2660);
DISPLAY 0.617021 (-7485 2660);
PAINT ORANGE (-7485 2660);
FORCEPROP 2 LASTPIN (-7475 2600) $PN DP9
J 2
(-7485 2610);
DISPLAY 0.617021 (-7485 2610);
PAINT ORANGE (-7485 2610);
FORCEPROP 2 LASTPIN (-7475 2550) $PN DP63
J 2
(-7485 2560);
DISPLAY 0.617021 (-7485 2560);
PAINT ORANGE (-7485 2560);
FORCEPROP 2 LASTPIN (-7475 2500) $PN DP61
J 2
(-7485 2510);
DISPLAY 0.617021 (-7485 2510);
PAINT ORANGE (-7485 2510);
FORCEPROP 2 LASTPIN (-7475 2450) $PN DP59
J 2
(-7485 2460);
DISPLAY 0.617021 (-7485 2460);
PAINT ORANGE (-7485 2460);
FORCEPROP 2 LASTPIN (-7475 2400) $PN DP57
J 2
(-7485 2410);
DISPLAY 0.617021 (-7485 2410);
PAINT ORANGE (-7485 2410);
FORCEPROP 2 LASTPIN (-7475 2350) $PN DP55
J 2
(-7485 2360);
DISPLAY 0.617021 (-7485 2360);
PAINT ORANGE (-7485 2360);
FORCEPROP 2 LASTPIN (-7475 2300) $PN DP53
J 2
(-7485 2310);
DISPLAY 0.617021 (-7485 2310);
PAINT ORANGE (-7485 2310);
FORCEPROP 2 LASTPIN (-7475 2250) $PN DP51
J 2
(-7485 2260);
DISPLAY 0.617021 (-7485 2260);
PAINT ORANGE (-7485 2260);
FORCEPROP 2 LASTPIN (-7475 2200) $PN DP49
J 2
(-7485 2210);
DISPLAY 0.617021 (-7485 2210);
PAINT ORANGE (-7485 2210);
FORCEPROP 2 LASTPIN (-7475 2150) $PN DP47
J 2
(-7485 2160);
DISPLAY 0.617021 (-7485 2160);
PAINT ORANGE (-7485 2160);
FORCEPROP 2 LASTPIN (-7475 2100) $PN DP45
J 2
(-7485 2110);
DISPLAY 0.617021 (-7485 2110);
PAINT ORANGE (-7485 2110);
FORCEPROP 2 LASTPIN (-7475 2050) $PN DN18
J 2
(-7485 2060);
DISPLAY 0.617021 (-7485 2060);
PAINT ORANGE (-7485 2060);
FORCEPROP 2 LASTPIN (-7475 2000) $PN DL8
J 2
(-7485 2010);
DISPLAY 0.617021 (-7485 2010);
PAINT ORANGE (-7485 2010);
FORCEPROP 2 LASTPIN (-7475 1950) $PN DE62
J 2
(-7485 1960);
DISPLAY 0.617021 (-7485 1960);
PAINT ORANGE (-7485 1960);
FORCEPROP 2 LASTPIN (-7475 1900) $PN DE60
J 2
(-7485 1910);
DISPLAY 0.617021 (-7485 1910);
PAINT ORANGE (-7485 1910);
FORCEPROP 2 LASTPIN (-7475 1850) $PN DE58
J 2
(-7485 1860);
DISPLAY 0.617021 (-7485 1860);
PAINT ORANGE (-7485 1860);
FORCEPROP 2 LASTPIN (-7475 1800) $PN DE56
J 2
(-7485 1810);
DISPLAY 0.617021 (-7485 1810);
PAINT ORANGE (-7485 1810);
FORCEPROP 2 LASTPIN (-7475 1750) $PN DE54
J 2
(-7485 1760);
DISPLAY 0.617021 (-7485 1760);
PAINT ORANGE (-7485 1760);
FORCEPROP 2 LASTPIN (-7475 1700) $PN DE52
J 2
(-7485 1710);
DISPLAY 0.617021 (-7485 1710);
PAINT ORANGE (-7485 1710);
FORCEPROP 2 LASTPIN (-7475 1650) $PN DE50
J 2
(-7485 1660);
DISPLAY 0.617021 (-7485 1660);
PAINT ORANGE (-7485 1660);
FORCEPROP 2 LASTPIN (-7475 1600) $PN DE48
J 2
(-7485 1610);
DISPLAY 0.617021 (-7485 1610);
PAINT ORANGE (-7485 1610);
FORCEPROP 2 LASTPIN (-7475 1550) $PN CW6
J 2
(-7485 1560);
DISPLAY 0.617021 (-7485 1560);
PAINT ORANGE (-7485 1560);
FORCEPROP 2 LASTPIN (-7475 1500) $PN CG6
J 2
(-7485 1510);
DISPLAY 0.617021 (-7485 1510);
PAINT ORANGE (-7485 1510);
FORCEPROP 2 LASTPIN (-7475 1450) $PN AR6
J 2
(-7485 1460);
DISPLAY 0.617021 (-7485 1460);
PAINT ORANGE (-7485 1460);
FORCEPROP 2 LASTPIN (-7475 1400) $PN AJ4
J 2
(-7485 1410);
DISPLAY 0.617021 (-7485 1410);
PAINT ORANGE (-7485 1410);
FORCEPROP 2 LASTPIN (-7475 1350) $PN AC62
J 2
(-7485 1360);
DISPLAY 0.617021 (-7485 1360);
PAINT ORANGE (-7485 1360);
FORCEPROP 2 LASTPIN (-7475 1300) $PN AC60
J 2
(-7485 1310);
DISPLAY 0.617021 (-7485 1310);
PAINT ORANGE (-7485 1310);
FORCEPROP 2 LASTPIN (-7475 1250) $PN AC58
J 2
(-7485 1260);
DISPLAY 0.617021 (-7485 1260);
PAINT ORANGE (-7485 1260);
FORCEPROP 2 LASTPIN (-7475 1200) $PN A26
J 2
(-7485 1210);
DISPLAY 0.617021 (-7485 1210);
PAINT ORANGE (-7485 1210);
FORCEPROP 2 LASTPIN (-7475 1150) $PN A30
J 2
(-7485 1160);
DISPLAY 0.617021 (-7485 1160);
PAINT ORANGE (-7485 1160);
FORCEPROP 2 LASTPIN (-7475 1100) $PN A32
J 2
(-7485 1110);
DISPLAY 0.617021 (-7485 1110);
PAINT ORANGE (-7485 1110);
FORCEPROP 2 LASTPIN (-7475 1050) $PN A36
J 2
(-7485 1060);
DISPLAY 0.617021 (-7485 1060);
PAINT ORANGE (-7485 1060);
FORCEPROP 2 LASTPIN (-7475 1000) $PN A38
J 2
(-7485 1010);
DISPLAY 0.617021 (-7485 1010);
PAINT ORANGE (-7485 1010);
FORCEPROP 2 LASTPIN (-7475 950) $PN B25
J 2
(-7485 960);
DISPLAY 0.617021 (-7485 960);
PAINT ORANGE (-7485 960);
FORCEPROP 2 LASTPIN (-7475 900) $PN B31
J 2
(-7485 910);
DISPLAY 0.617021 (-7485 910);
PAINT ORANGE (-7485 910);
FORCEPROP 2 LASTPIN (-7475 850) $PN B37
J 2
(-7485 860);
DISPLAY 0.617021 (-7485 860);
PAINT ORANGE (-7485 860);
FORCEPROP 2 LASTPIN (-7475 800) $PN B71
J 2
(-7485 810);
DISPLAY 0.617021 (-7485 810);
PAINT ORANGE (-7485 810);
FORCEPROP 2 LASTPIN (-7475 750) $PN B75
J 2
(-7485 760);
DISPLAY 0.617021 (-7485 760);
PAINT ORANGE (-7485 760);
FORCEPROP 2 LASTPIN (-7475 700) $PN C8
J 2
(-7485 710);
DISPLAY 0.617021 (-7485 710);
PAINT ORANGE (-7485 710);
FORCEPROP 2 LASTPIN (-7475 650) $PN C10
J 2
(-7485 660);
DISPLAY 0.617021 (-7485 660);
PAINT ORANGE (-7485 660);
FORCEPROP 2 LASTPIN (-6275 4600) $PN C12
J 0
(-6265 4610);
DISPLAY 0.617021 (-6265 4610);
PAINT ORANGE (-6265 4610);
FORCEPROP 2 LASTPIN (-6275 4550) $PN C14
J 0
(-6265 4560);
DISPLAY 0.617021 (-6265 4560);
PAINT ORANGE (-6265 4560);
FORCEPROP 2 LASTPIN (-6275 4500) $PN C16
J 0
(-6265 4510);
DISPLAY 0.617021 (-6265 4510);
PAINT ORANGE (-6265 4510);
FORCEPROP 2 LASTPIN (-6275 4450) $PN C76
J 0
(-6265 4460);
DISPLAY 0.617021 (-6265 4460);
PAINT ORANGE (-6265 4460);
FORCEPROP 2 LASTPIN (-6275 4400) $PN C78
J 0
(-6265 4410);
DISPLAY 0.617021 (-6265 4410);
PAINT ORANGE (-6265 4410);
FORCEPROP 2 LASTPIN (-6275 4350) $PN CM27
J 0
(-6265 4360);
DISPLAY 0.617021 (-6265 4360);
PAINT ORANGE (-6265 4360);
FORCEPROP 2 LASTPIN (-6275 4300) $PN D11
J 0
(-6265 4310);
DISPLAY 0.617021 (-6265 4310);
PAINT ORANGE (-6265 4310);
FORCEPROP 2 LASTPIN (-6275 4250) $PN D13
J 0
(-6265 4260);
DISPLAY 0.617021 (-6265 4260);
PAINT ORANGE (-6265 4260);
FORCEPROP 2 LASTPIN (-6275 4200) $PN D25
J 0
(-6265 4210);
DISPLAY 0.617021 (-6265 4210);
PAINT ORANGE (-6265 4210);
FORCEPROP 2 LASTPIN (-6275 4150) $PN D27
J 0
(-6265 4160);
DISPLAY 0.617021 (-6265 4160);
PAINT ORANGE (-6265 4160);
FORCEPROP 2 LASTPIN (-6275 4100) $PN D29
J 0
(-6265 4110);
DISPLAY 0.617021 (-6265 4110);
PAINT ORANGE (-6265 4110);
FORCEPROP 2 LASTPIN (-6275 4050) $PN D31
J 0
(-6265 4060);
DISPLAY 0.617021 (-6265 4060);
PAINT ORANGE (-6265 4060);
FORCEPROP 2 LASTPIN (-6275 4000) $PN D33
J 0
(-6265 4010);
DISPLAY 0.617021 (-6265 4010);
PAINT ORANGE (-6265 4010);
FORCEPROP 2 LASTPIN (-6275 3950) $PN D35
J 0
(-6265 3960);
DISPLAY 0.617021 (-6265 3960);
PAINT ORANGE (-6265 3960);
FORCEPROP 2 LASTPIN (-6275 3900) $PN D37
J 0
(-6265 3910);
DISPLAY 0.617021 (-6265 3910);
PAINT ORANGE (-6265 3910);
FORCEPROP 2 LASTPIN (-6275 3850) $PN D39
J 0
(-6265 3860);
DISPLAY 0.617021 (-6265 3860);
PAINT ORANGE (-6265 3860);
FORCEPROP 2 LASTPIN (-6275 3800) $PN D41
J 0
(-6265 3810);
DISPLAY 0.617021 (-6265 3810);
PAINT ORANGE (-6265 3810);
FORCEPROP 2 LASTPIN (-6275 3750) $PN D43
J 0
(-6265 3760);
DISPLAY 0.617021 (-6265 3760);
PAINT ORANGE (-6265 3760);
FORCEPROP 2 LASTPIN (-6275 3700) $PN D77
J 0
(-6265 3710);
DISPLAY 0.617021 (-6265 3710);
PAINT ORANGE (-6265 3710);
FORCEPROP 2 LASTPIN (-6275 3650) $PN E6
J 0
(-6265 3660);
DISPLAY 0.617021 (-6265 3660);
PAINT ORANGE (-6265 3660);
FORCEPROP 2 LASTPIN (-6275 3600) $PN E8
J 0
(-6265 3610);
DISPLAY 0.617021 (-6265 3610);
PAINT ORANGE (-6265 3610);
FORCEPROP 2 LASTPIN (-6275 3550) $PN E16
J 0
(-6265 3560);
DISPLAY 0.617021 (-6265 3560);
PAINT ORANGE (-6265 3560);
FORCEPROP 2 LASTPIN (-6275 3500) $PN E18
J 0
(-6265 3510);
DISPLAY 0.617021 (-6265 3510);
PAINT ORANGE (-6265 3510);
FORCEPROP 2 LASTPIN (-6275 3450) $PN E20
J 0
(-6265 3460);
DISPLAY 0.617021 (-6265 3460);
PAINT ORANGE (-6265 3460);
FORCEPROP 2 LASTPIN (-6275 3400) $PN E22
J 0
(-6265 3410);
DISPLAY 0.617021 (-6265 3410);
PAINT ORANGE (-6265 3410);
FORCEPROP 2 LASTPIN (-6275 3350) $PN E72
J 0
(-6265 3360);
DISPLAY 0.617021 (-6265 3360);
PAINT ORANGE (-6265 3360);
FORCEPROP 2 LASTPIN (-6275 3300) $PN E74
J 0
(-6265 3310);
DISPLAY 0.617021 (-6265 3310);
PAINT ORANGE (-6265 3310);
FORCEPROP 2 LASTPIN (-6275 3250) $PN E76
J 0
(-6265 3260);
DISPLAY 0.617021 (-6265 3260);
PAINT ORANGE (-6265 3260);
FORCEPROP 2 LASTPIN (-6275 3200) $PN F5
J 0
(-6265 3210);
DISPLAY 0.617021 (-6265 3210);
PAINT ORANGE (-6265 3210);
FORCEPROP 2 LASTPIN (-6275 3150) $PN F17
J 0
(-6265 3160);
DISPLAY 0.617021 (-6265 3160);
PAINT ORANGE (-6265 3160);
FORCEPROP 2 LASTPIN (-6275 3100) $PN F19
J 0
(-6265 3110);
DISPLAY 0.617021 (-6265 3110);
PAINT ORANGE (-6265 3110);
FORCEPROP 2 LASTPIN (-6275 3050) $PN F25
J 0
(-6265 3060);
DISPLAY 0.617021 (-6265 3060);
PAINT ORANGE (-6265 3060);
FORCEPROP 2 LASTPIN (-6275 3000) $PN F31
J 0
(-6265 3010);
DISPLAY 0.617021 (-6265 3010);
PAINT ORANGE (-6265 3010);
FORCEPROP 2 LASTPIN (-6275 2950) $PN F37
J 0
(-6265 2960);
DISPLAY 0.617021 (-6265 2960);
PAINT ORANGE (-6265 2960);
FORCEPROP 2 LASTPIN (-6275 2900) $PN F43
J 0
(-6265 2910);
DISPLAY 0.617021 (-6265 2910);
PAINT ORANGE (-6265 2910);
FORCEPROP 2 LASTPIN (-6275 2850) $PN F67
J 0
(-6265 2860);
DISPLAY 0.617021 (-6265 2860);
PAINT ORANGE (-6265 2860);
FORCEPROP 2 LASTPIN (-6275 2800) $PN F69
J 0
(-6265 2810);
DISPLAY 0.617021 (-6265 2810);
PAINT ORANGE (-6265 2810);
FORCEPROP 2 LASTPIN (-6275 2750) $PN G4
J 0
(-6265 2760);
DISPLAY 0.617021 (-6265 2760);
PAINT ORANGE (-6265 2760);
FORCEPROP 2 LASTPIN (-6275 2700) $PN G8
J 0
(-6265 2710);
DISPLAY 0.617021 (-6265 2710);
PAINT ORANGE (-6265 2710);
FORCEPROP 2 LASTPIN (-6275 2650) $PN G22
J 0
(-6265 2660);
DISPLAY 0.617021 (-6265 2660);
PAINT ORANGE (-6265 2660);
FORCEPROP 2 LASTPIN (-6275 2600) $PN G24
J 0
(-6265 2610);
DISPLAY 0.617021 (-6265 2610);
PAINT ORANGE (-6265 2610);
FORCEPROP 2 LASTPIN (-6275 2550) $PN G26
J 0
(-6265 2560);
DISPLAY 0.617021 (-6265 2560);
PAINT ORANGE (-6265 2560);
FORCEPROP 2 LASTPIN (-6275 2500) $PN G30
J 0
(-6265 2510);
DISPLAY 0.617021 (-6265 2510);
PAINT ORANGE (-6265 2510);
FORCEPROP 2 LASTPIN (-6275 2450) $PN G32
J 0
(-6265 2460);
DISPLAY 0.617021 (-6265 2460);
PAINT ORANGE (-6265 2460);
FORCEPROP 2 LASTPIN (-6275 2400) $PN G36
J 0
(-6265 2410);
DISPLAY 0.617021 (-6265 2410);
PAINT ORANGE (-6265 2410);
FORCEPROP 2 LASTPIN (-6275 2350) $PN G38
J 0
(-6265 2360);
DISPLAY 0.617021 (-6265 2360);
PAINT ORANGE (-6265 2360);
FORCEPROP 2 LASTPIN (-6275 2300) $PN G42
J 0
(-6265 2310);
DISPLAY 0.617021 (-6265 2310);
PAINT ORANGE (-6265 2310);
FORCEPROP 2 LASTPIN (-6275 2250) $PN G66
J 0
(-6265 2260);
DISPLAY 0.617021 (-6265 2260);
PAINT ORANGE (-6265 2260);
FORCEPROP 2 LASTPIN (-6275 2200) $PN G70
J 0
(-6265 2210);
DISPLAY 0.617021 (-6265 2210);
PAINT ORANGE (-6265 2210);
FORCEPROP 2 LASTPIN (-6275 2150) $PN G76
J 0
(-6265 2160);
DISPLAY 0.617021 (-6265 2160);
PAINT ORANGE (-6265 2160);
FORCEPROP 2 LASTPIN (-6275 2100) $PN G78
J 0
(-6265 2110);
DISPLAY 0.617021 (-6265 2110);
PAINT ORANGE (-6265 2110);
FORCEPROP 2 LASTPIN (-6275 2050) $PN G80
J 0
(-6265 2060);
DISPLAY 0.617021 (-6265 2060);
PAINT ORANGE (-6265 2060);
FORCEPROP 2 LASTPIN (-6275 2000) $PN G82
J 0
(-6265 2010);
DISPLAY 0.617021 (-6265 2010);
PAINT ORANGE (-6265 2010);
FORCEPROP 2 LASTPIN (-6275 1950) $PN H3
J 0
(-6265 1960);
DISPLAY 0.617021 (-6265 1960);
PAINT ORANGE (-6265 1960);
FORCEPROP 2 LASTPIN (-6275 1900) $PN H11
J 0
(-6265 1910);
DISPLAY 0.617021 (-6265 1910);
PAINT ORANGE (-6265 1910);
FORCEPROP 2 LASTPIN (-6275 1850) $PN H25
J 0
(-6265 1860);
DISPLAY 0.617021 (-6265 1860);
PAINT ORANGE (-6265 1860);
FORCEPROP 2 LASTPIN (-6275 1800) $PN H27
J 0
(-6265 1810);
DISPLAY 0.617021 (-6265 1810);
PAINT ORANGE (-6265 1810);
FORCEPROP 2 LASTPIN (-6275 1750) $PN H29
J 0
(-6265 1760);
DISPLAY 0.617021 (-6265 1760);
PAINT ORANGE (-6265 1760);
FORCEPROP 2 LASTPIN (-6275 1700) $PN H31
J 0
(-6265 1710);
DISPLAY 0.617021 (-6265 1710);
PAINT ORANGE (-6265 1710);
FORCEPROP 2 LASTPIN (-6275 1650) $PN H33
J 0
(-6265 1660);
DISPLAY 0.617021 (-6265 1660);
PAINT ORANGE (-6265 1660);
FORCEPROP 2 LASTPIN (-6275 1600) $PN H35
J 0
(-6265 1610);
DISPLAY 0.617021 (-6265 1610);
PAINT ORANGE (-6265 1610);
FORCEPROP 2 LASTPIN (-6275 1550) $PN H37
J 0
(-6265 1560);
DISPLAY 0.617021 (-6265 1560);
PAINT ORANGE (-6265 1560);
FORCEPROP 2 LASTPIN (-6275 1500) $PN H39
J 0
(-6265 1510);
DISPLAY 0.617021 (-6265 1510);
PAINT ORANGE (-6265 1510);
FORCEPROP 2 LASTPIN (-6275 1450) $PN H41
J 0
(-6265 1460);
DISPLAY 0.617021 (-6265 1460);
PAINT ORANGE (-6265 1460);
FORCEPROP 2 LASTPIN (-6275 1400) $PN H65
J 0
(-6265 1410);
DISPLAY 0.617021 (-6265 1410);
PAINT ORANGE (-6265 1410);
FORCEPROP 2 LASTPIN (-6275 1350) $PN H71
J 0
(-6265 1360);
DISPLAY 0.617021 (-6265 1360);
PAINT ORANGE (-6265 1360);
FORCEPROP 2 LASTPIN (-6275 1300) $PN H75
J 0
(-6265 1310);
DISPLAY 0.617021 (-6265 1310);
PAINT ORANGE (-6265 1310);
FORCEPROP 2 LASTPIN (-6275 1250) $PN DN44
J 0
(-6265 1260);
DISPLAY 0.617021 (-6265 1260);
PAINT ORANGE (-6265 1260);
FORCEPROP 2 LASTPIN (-6275 1200) $PN J4
J 0
(-6265 1210);
DISPLAY 0.617021 (-6265 1210);
PAINT ORANGE (-6265 1210);
FORCEPROP 2 LASTPIN (-6275 1150) $PN J12
J 0
(-6265 1160);
DISPLAY 0.617021 (-6265 1160);
PAINT ORANGE (-6265 1160);
FORCEPROP 2 LASTPIN (-6275 1100) $PN J14
J 0
(-6265 1110);
DISPLAY 0.617021 (-6265 1110);
PAINT ORANGE (-6265 1110);
FORCEPROP 2 LASTPIN (-6275 1050) $PN J22
J 0
(-6265 1060);
DISPLAY 0.617021 (-6265 1060);
PAINT ORANGE (-6265 1060);
FORCEPROP 2 LASTPIN (-6275 1000) $PN J26
J 0
(-6265 1010);
DISPLAY 0.617021 (-6265 1010);
PAINT ORANGE (-6265 1010);
FORCEPROP 2 LASTPIN (-6275 950) $PN J28
J 0
(-6265 960);
DISPLAY 0.617021 (-6265 960);
PAINT ORANGE (-6265 960);
FORCEPROP 2 LASTPIN (-6275 900) $PN J32
J 0
(-6265 910);
DISPLAY 0.617021 (-6265 910);
PAINT ORANGE (-6265 910);
FORCEPROP 2 LASTPIN (-6275 850) $PN J34
J 0
(-6265 860);
DISPLAY 0.617021 (-6265 860);
PAINT ORANGE (-6265 860);
FORCEPROP 2 LASTPIN (-6275 800) $PN J38
J 0
(-6265 810);
DISPLAY 0.617021 (-6265 810);
PAINT ORANGE (-6265 810);
FORCEPROP 2 LASTPIN (-6275 750) $PN J40
J 0
(-6265 760);
DISPLAY 0.617021 (-6265 760);
PAINT ORANGE (-6265 760);
FORCEPROP 2 LASTPIN (-6275 700) $PN J72
J 0
(-6265 710);
DISPLAY 0.617021 (-6265 710);
PAINT ORANGE (-6265 710);
FORCEPROP 2 LASTPIN (-6275 650) $PN J74
J 0
(-6265 660);
DISPLAY 0.617021 (-6265 660);
PAINT ORANGE (-6265 660);
FORCEPROP 2 LASTPIN (-7475 4600) $PN B9
J 2
(-7485 4610);
DISPLAY 0.617021 (-7485 4610);
PAINT ORANGE (-7485 4610);
FORCEPROP 1 LAST PACK_TYPE BGA1
J 0
(-7425 4900);
PAINT SKYBLUE (-7425 4900);
DISPLAY INVISIBLE (-7425 4900);
FORCEPROP 2 LAST SEC_TYPE BGA1
J 0
(-7425 4900);
DISPLAY 1.021277 (-7425 4900);
PAINT ORANGE (-7425 4900);
DISPLAY INVISIBLE (-7425 4900);
FORCEPROP 2 LAST CDS_LIB chpset_lib
J 0
(-6875 2600);
PAINT ORANGE (-6875 2600);
DISPLAY INVISIBLE (-6875 2600);
FORCEPROP 2 LAST SEC 23
J 0
(-7425 4900);
DISPLAY 0.680851 (-7425 4900);
PAINT MONO (-7425 4900);
DISPLAY INVISIBLE (-7425 4900);
FORCEPROP 2 LAST CDS_LOCATION U2D1
J 0
(-7425 4850);
DISPLAY 0.617021 (-7425 4850);
PAINT AQUA (-7425 4850);
DISPLAY INVISIBLE (-7425 4850);
FORCEPROP 1 LAST PATH I20
J 0
(-6875 4800);
PAINT GREEN (-6875 4800);
DISPLAY INVISIBLE (-6875 4800);
FORCEADD SKX_EXT_B..24
(-5025 2625);
FORCEPROP 1 LAST LOCATION U2D1
J 0
(-5575 4875);
DISPLAY 0.617021 (-5575 4875);
PAINT AQUA (-5575 4875);
FORCEPROP 1 LAST PART_NUMBER TBD
J 0
(-5575 475);
DISPLAY 0.617021 (-5575 475);
PAINT BLUE (-5575 475);
FORCEPROP 1 LAST MATERIAL IC
J 0
(-5575 4825);
DISPLAY 0.617021 (-5575 4825);
PAINT SKYBLUE (-5575 4825);
FORCEPROP 2 LASTPIN (-5625 4625) $PN J76
J 2
(-5635 4635);
DISPLAY 0.617021 (-5635 4635);
PAINT ORANGE (-5635 4635);
FORCEPROP 2 LASTPIN (-5625 4575) $PN J82
J 2
(-5635 4585);
DISPLAY 0.617021 (-5635 4585);
PAINT ORANGE (-5635 4585);
FORCEPROP 2 LASTPIN (-5625 4525) $PN J84
J 2
(-5635 4535);
DISPLAY 0.617021 (-5635 4535);
PAINT ORANGE (-5635 4535);
FORCEPROP 2 LASTPIN (-5625 4475) $PN K1
J 2
(-5635 4485);
DISPLAY 0.617021 (-5635 4485);
PAINT ORANGE (-5635 4485);
FORCEPROP 2 LASTPIN (-5625 4425) $PN K11
J 2
(-5635 4435);
DISPLAY 0.617021 (-5635 4435);
PAINT ORANGE (-5635 4435);
FORCEPROP 2 LASTPIN (-5625 4375) $PN K13
J 2
(-5635 4385);
DISPLAY 0.617021 (-5635 4385);
PAINT ORANGE (-5635 4385);
FORCEPROP 2 LASTPIN (-5625 4325) $PN K17
J 2
(-5635 4335);
DISPLAY 0.617021 (-5635 4335);
PAINT ORANGE (-5635 4335);
FORCEPROP 2 LASTPIN (-5625 4275) $PN DB7
J 2
(-5635 4285);
DISPLAY 0.617021 (-5635 4285);
PAINT ORANGE (-5635 4285);
FORCEPROP 2 LASTPIN (-5625 4225) $PN K27
J 2
(-5635 4235);
DISPLAY 0.617021 (-5635 4235);
PAINT ORANGE (-5635 4235);
FORCEPROP 2 LASTPIN (-5625 4175) $PN K33
J 2
(-5635 4185);
DISPLAY 0.617021 (-5635 4185);
PAINT ORANGE (-5635 4185);
FORCEPROP 2 LASTPIN (-5625 4125) $PN K39
J 2
(-5635 4135);
DISPLAY 0.617021 (-5635 4135);
PAINT ORANGE (-5635 4135);
FORCEPROP 2 LASTPIN (-5625 4075) $PN K65
J 2
(-5635 4085);
DISPLAY 0.617021 (-5635 4085);
PAINT ORANGE (-5635 4085);
FORCEPROP 2 LASTPIN (-5625 4025) $PN K67
J 2
(-5635 4035);
DISPLAY 0.617021 (-5635 4035);
PAINT ORANGE (-5635 4035);
FORCEPROP 2 LASTPIN (-5625 3975) $PN K69
J 2
(-5635 3985);
DISPLAY 0.617021 (-5635 3985);
PAINT ORANGE (-5635 3985);
FORCEPROP 2 LASTPIN (-5625 3925) $PN K71
J 2
(-5635 3935);
DISPLAY 0.617021 (-5635 3935);
PAINT ORANGE (-5635 3935);
FORCEPROP 2 LASTPIN (-5625 3875) $PN K73
J 2
(-5635 3885);
DISPLAY 0.617021 (-5635 3885);
PAINT ORANGE (-5635 3885);
FORCEPROP 2 LASTPIN (-5625 3825) $PN K77
J 2
(-5635 3835);
DISPLAY 0.617021 (-5635 3835);
PAINT ORANGE (-5635 3835);
FORCEPROP 2 LASTPIN (-5625 3775) $PN K81
J 2
(-5635 3785);
DISPLAY 0.617021 (-5635 3785);
PAINT ORANGE (-5635 3785);
FORCEPROP 2 LASTPIN (-5625 3725) $PN K83
J 2
(-5635 3735);
DISPLAY 0.617021 (-5635 3735);
PAINT ORANGE (-5635 3735);
FORCEPROP 2 LASTPIN (-5625 3675) $PN K85
J 2
(-5635 3685);
DISPLAY 0.617021 (-5635 3685);
PAINT ORANGE (-5635 3685);
FORCEPROP 2 LASTPIN (-5625 3625) $PN L10
J 2
(-5635 3635);
DISPLAY 0.617021 (-5635 3635);
PAINT ORANGE (-5635 3635);
FORCEPROP 2 LASTPIN (-5625 3575) $PN L2
J 2
(-5635 3585);
DISPLAY 0.617021 (-5635 3585);
PAINT ORANGE (-5635 3585);
FORCEPROP 2 LASTPIN (-5625 3525) $PN L6
J 2
(-5635 3535);
DISPLAY 0.617021 (-5635 3535);
PAINT ORANGE (-5635 3535);
FORCEPROP 2 LASTPIN (-5625 3475) $PN L20
J 2
(-5635 3485);
DISPLAY 0.617021 (-5635 3485);
PAINT ORANGE (-5635 3485);
FORCEPROP 2 LASTPIN (-5625 3425) $PN L22
J 2
(-5635 3435);
DISPLAY 0.617021 (-5635 3435);
PAINT ORANGE (-5635 3435);
FORCEPROP 2 LASTPIN (-5625 3375) $PN L72
J 2
(-5635 3385);
DISPLAY 0.617021 (-5635 3385);
PAINT ORANGE (-5635 3385);
FORCEPROP 2 LASTPIN (-5625 3325) $PN L78
J 2
(-5635 3335);
DISPLAY 0.617021 (-5635 3335);
PAINT ORANGE (-5635 3335);
FORCEPROP 2 LASTPIN (-5625 3275) $PN L80
J 2
(-5635 3285);
DISPLAY 0.617021 (-5635 3285);
PAINT ORANGE (-5635 3285);
FORCEPROP 2 LASTPIN (-5625 3225) $PN L82
J 2
(-5635 3235);
DISPLAY 0.617021 (-5635 3235);
PAINT ORANGE (-5635 3235);
FORCEPROP 2 LASTPIN (-5625 3175) $PN BT9
J 2
(-5635 3185);
DISPLAY 0.617021 (-5635 3185);
PAINT ORANGE (-5635 3185);
FORCEPROP 2 LASTPIN (-5625 3125) $PN CT7
J 2
(-5635 3135);
DISPLAY 0.617021 (-5635 3135);
PAINT ORANGE (-5635 3135);
FORCEPROP 2 LASTPIN (-5625 3075) $PN M15
J 2
(-5635 3085);
DISPLAY 0.617021 (-5635 3085);
PAINT ORANGE (-5635 3085);
FORCEPROP 2 LASTPIN (-5625 3025) $PN M17
J 2
(-5635 3035);
DISPLAY 0.617021 (-5635 3035);
PAINT ORANGE (-5635 3035);
FORCEPROP 2 LASTPIN (-5625 2975) $PN M19
J 2
(-5635 2985);
DISPLAY 0.617021 (-5635 2985);
PAINT ORANGE (-5635 2985);
FORCEPROP 2 LASTPIN (-5625 2925) $PN M23
J 2
(-5635 2935);
DISPLAY 0.617021 (-5635 2935);
PAINT ORANGE (-5635 2935);
FORCEPROP 2 LASTPIN (-5625 2875) $PN M25
J 2
(-5635 2885);
DISPLAY 0.617021 (-5635 2885);
PAINT ORANGE (-5635 2885);
FORCEPROP 2 LASTPIN (-5625 2825) $PN M27
J 2
(-5635 2835);
DISPLAY 0.617021 (-5635 2835);
PAINT ORANGE (-5635 2835);
FORCEPROP 2 LASTPIN (-5625 2775) $PN M29
J 2
(-5635 2785);
DISPLAY 0.617021 (-5635 2785);
PAINT ORANGE (-5635 2785);
FORCEPROP 2 LASTPIN (-5625 2725) $PN M31
J 2
(-5635 2735);
DISPLAY 0.617021 (-5635 2735);
PAINT ORANGE (-5635 2735);
FORCEPROP 2 LASTPIN (-5625 2675) $PN M33
J 2
(-5635 2685);
DISPLAY 0.617021 (-5635 2685);
PAINT ORANGE (-5635 2685);
FORCEPROP 2 LASTPIN (-5625 2625) $PN M35
J 2
(-5635 2635);
DISPLAY 0.617021 (-5635 2635);
PAINT ORANGE (-5635 2635);
FORCEPROP 2 LASTPIN (-5625 2575) $PN M37
J 2
(-5635 2585);
DISPLAY 0.617021 (-5635 2585);
PAINT ORANGE (-5635 2585);
FORCEPROP 2 LASTPIN (-5625 2525) $PN M39
J 2
(-5635 2535);
DISPLAY 0.617021 (-5635 2535);
PAINT ORANGE (-5635 2535);
FORCEPROP 2 LASTPIN (-5625 2475) $PN M41
J 2
(-5635 2485);
DISPLAY 0.617021 (-5635 2485);
PAINT ORANGE (-5635 2485);
FORCEPROP 2 LASTPIN (-5625 2425) $PN M43
J 2
(-5635 2435);
DISPLAY 0.617021 (-5635 2435);
PAINT ORANGE (-5635 2435);
FORCEPROP 2 LASTPIN (-5625 2375) $PN M65
J 2
(-5635 2385);
DISPLAY 0.617021 (-5635 2385);
PAINT ORANGE (-5635 2385);
FORCEPROP 2 LASTPIN (-5625 2325) $PN M71
J 2
(-5635 2335);
DISPLAY 0.617021 (-5635 2335);
PAINT ORANGE (-5635 2335);
FORCEPROP 2 LASTPIN (-5625 2275) $PN M79
J 2
(-5635 2285);
DISPLAY 0.617021 (-5635 2285);
PAINT ORANGE (-5635 2285);
FORCEPROP 2 LASTPIN (-5625 2225) $PN M83
J 2
(-5635 2235);
DISPLAY 0.617021 (-5635 2235);
PAINT ORANGE (-5635 2235);
FORCEPROP 2 LASTPIN (-5625 2175) $PN M85
J 2
(-5635 2185);
DISPLAY 0.617021 (-5635 2185);
PAINT ORANGE (-5635 2185);
FORCEPROP 2 LASTPIN (-5625 2125) $PN DM19
J 2
(-5635 2135);
DISPLAY 0.617021 (-5635 2135);
PAINT ORANGE (-5635 2135);
FORCEPROP 2 LASTPIN (-5625 2075) $PN N20
J 2
(-5635 2085);
DISPLAY 0.617021 (-5635 2085);
PAINT ORANGE (-5635 2085);
FORCEPROP 2 LASTPIN (-5625 2025) $PN N22
J 2
(-5635 2035);
DISPLAY 0.617021 (-5635 2035);
PAINT ORANGE (-5635 2035);
FORCEPROP 2 LASTPIN (-5625 1975) $PN N6
J 2
(-5635 1985);
DISPLAY 0.617021 (-5635 1985);
PAINT ORANGE (-5635 1985);
FORCEPROP 2 LASTPIN (-5625 1925) $PN N66
J 2
(-5635 1935);
DISPLAY 0.617021 (-5635 1935);
PAINT ORANGE (-5635 1935);
FORCEPROP 2 LASTPIN (-5625 1875) $PN N70
J 2
(-5635 1885);
DISPLAY 0.617021 (-5635 1885);
PAINT ORANGE (-5635 1885);
FORCEPROP 2 LASTPIN (-5625 1825) $PN N72
J 2
(-5635 1835);
DISPLAY 0.617021 (-5635 1835);
PAINT ORANGE (-5635 1835);
FORCEPROP 2 LASTPIN (-5625 1775) $PN N74
J 2
(-5635 1785);
DISPLAY 0.617021 (-5635 1785);
PAINT ORANGE (-5635 1785);
FORCEPROP 2 LASTPIN (-5625 1725) $PN N76
J 2
(-5635 1735);
DISPLAY 0.617021 (-5635 1735);
PAINT ORANGE (-5635 1735);
FORCEPROP 2 LASTPIN (-5625 1675) $PN N78
J 2
(-5635 1685);
DISPLAY 0.617021 (-5635 1685);
PAINT ORANGE (-5635 1685);
FORCEPROP 2 LASTPIN (-5625 1625) $PN N4
J 2
(-5635 1635);
DISPLAY 0.617021 (-5635 1635);
PAINT ORANGE (-5635 1635);
FORCEPROP 2 LASTPIN (-5625 1575) $PN N8
J 2
(-5635 1585);
DISPLAY 0.617021 (-5635 1585);
PAINT ORANGE (-5635 1585);
FORCEPROP 2 LASTPIN (-5625 1525) $PN P11
J 2
(-5635 1535);
DISPLAY 0.617021 (-5635 1535);
PAINT ORANGE (-5635 1535);
FORCEPROP 2 LASTPIN (-5625 1475) $PN P15
J 2
(-5635 1485);
DISPLAY 0.617021 (-5635 1485);
PAINT ORANGE (-5635 1485);
FORCEPROP 2 LASTPIN (-5625 1425) $PN P27
J 2
(-5635 1435);
DISPLAY 0.617021 (-5635 1435);
PAINT ORANGE (-5635 1435);
FORCEPROP 2 LASTPIN (-5625 1375) $PN P33
J 2
(-5635 1385);
DISPLAY 0.617021 (-5635 1385);
PAINT ORANGE (-5635 1385);
FORCEPROP 2 LASTPIN (-5625 1325) $PN P39
J 2
(-5635 1335);
DISPLAY 0.617021 (-5635 1335);
PAINT ORANGE (-5635 1335);
FORCEPROP 2 LASTPIN (-5625 1275) $PN P67
J 2
(-5635 1285);
DISPLAY 0.617021 (-5635 1285);
PAINT ORANGE (-5635 1285);
FORCEPROP 2 LASTPIN (-5625 1225) $PN P69
J 2
(-5635 1235);
DISPLAY 0.617021 (-5635 1235);
PAINT ORANGE (-5635 1235);
FORCEPROP 2 LASTPIN (-5625 1175) $PN P71
J 2
(-5635 1185);
DISPLAY 0.617021 (-5635 1185);
PAINT ORANGE (-5635 1185);
FORCEPROP 2 LASTPIN (-5625 1125) $PN P81
J 2
(-5635 1135);
DISPLAY 0.617021 (-5635 1135);
PAINT ORANGE (-5635 1135);
FORCEPROP 2 LASTPIN (-5625 1075) $PN P83
J 2
(-5635 1085);
DISPLAY 0.617021 (-5635 1085);
PAINT ORANGE (-5635 1085);
FORCEPROP 2 LASTPIN (-5625 1025) $PN R14
J 2
(-5635 1035);
DISPLAY 0.617021 (-5635 1035);
PAINT ORANGE (-5635 1035);
FORCEPROP 2 LASTPIN (-5625 975) $PN R18
J 2
(-5635 985);
DISPLAY 0.617021 (-5635 985);
PAINT ORANGE (-5635 985);
FORCEPROP 2 LASTPIN (-5625 925) $PN R2
J 2
(-5635 935);
DISPLAY 0.617021 (-5635 935);
PAINT ORANGE (-5635 935);
FORCEPROP 2 LASTPIN (-5625 875) $PN R4
J 2
(-5635 885);
DISPLAY 0.617021 (-5635 885);
PAINT ORANGE (-5635 885);
FORCEPROP 2 LASTPIN (-5625 825) $PN R22
J 2
(-5635 835);
DISPLAY 0.617021 (-5635 835);
PAINT ORANGE (-5635 835);
FORCEPROP 2 LASTPIN (-5625 775) $PN R26
J 2
(-5635 785);
DISPLAY 0.617021 (-5635 785);
PAINT ORANGE (-5635 785);
FORCEPROP 2 LASTPIN (-5625 725) $PN R28
J 2
(-5635 735);
DISPLAY 0.617021 (-5635 735);
PAINT ORANGE (-5635 735);
FORCEPROP 2 LASTPIN (-5625 675) $PN R32
J 2
(-5635 685);
DISPLAY 0.617021 (-5635 685);
PAINT ORANGE (-5635 685);
FORCEPROP 2 LASTPIN (-4425 4625) $PN R34
J 0
(-4415 4635);
DISPLAY 0.617021 (-4415 4635);
PAINT ORANGE (-4415 4635);
FORCEPROP 2 LASTPIN (-4425 4575) $PN R38
J 0
(-4415 4585);
DISPLAY 0.617021 (-4415 4585);
PAINT ORANGE (-4415 4585);
FORCEPROP 2 LASTPIN (-4425 4525) $PN R40
J 0
(-4415 4535);
DISPLAY 0.617021 (-4415 4535);
PAINT ORANGE (-4415 4535);
FORCEPROP 2 LASTPIN (-4425 4475) $PN R68
J 0
(-4415 4485);
DISPLAY 0.617021 (-4415 4485);
PAINT ORANGE (-4415 4485);
FORCEPROP 2 LASTPIN (-4425 4425) $PN R72
J 0
(-4415 4435);
DISPLAY 0.617021 (-4415 4435);
PAINT ORANGE (-4415 4435);
FORCEPROP 2 LASTPIN (-4425 4375) $PN R78
J 0
(-4415 4385);
DISPLAY 0.617021 (-4415 4385);
PAINT ORANGE (-4415 4385);
FORCEPROP 2 LASTPIN (-4425 4325) $PN R86
J 0
(-4415 4335);
DISPLAY 0.617021 (-4415 4335);
PAINT ORANGE (-4415 4335);
FORCEPROP 2 LASTPIN (-4425 4275) $PN T13
J 0
(-4415 4285);
DISPLAY 0.617021 (-4415 4285);
PAINT ORANGE (-4415 4285);
FORCEPROP 2 LASTPIN (-4425 4225) $PN T17
J 0
(-4415 4235);
DISPLAY 0.617021 (-4415 4235);
PAINT ORANGE (-4415 4235);
FORCEPROP 2 LASTPIN (-4425 4175) $PN T25
J 0
(-4415 4185);
DISPLAY 0.617021 (-4415 4185);
PAINT ORANGE (-4415 4185);
FORCEPROP 2 LASTPIN (-4425 4125) $PN T29
J 0
(-4415 4135);
DISPLAY 0.617021 (-4415 4135);
PAINT ORANGE (-4415 4135);
FORCEPROP 2 LASTPIN (-4425 4075) $PN T31
J 0
(-4415 4085);
DISPLAY 0.617021 (-4415 4085);
PAINT ORANGE (-4415 4085);
FORCEPROP 2 LASTPIN (-4425 4025) $PN T35
J 0
(-4415 4035);
DISPLAY 0.617021 (-4415 4035);
PAINT ORANGE (-4415 4035);
FORCEPROP 2 LASTPIN (-4425 3975) $PN T37
J 0
(-4415 3985);
DISPLAY 0.617021 (-4415 3985);
PAINT ORANGE (-4415 3985);
FORCEPROP 2 LASTPIN (-4425 3925) $PN T41
J 0
(-4415 3935);
DISPLAY 0.617021 (-4415 3935);
PAINT ORANGE (-4415 3935);
FORCEPROP 2 LASTPIN (-4425 3875) $PN T65
J 0
(-4415 3885);
DISPLAY 0.617021 (-4415 3885);
PAINT ORANGE (-4415 3885);
FORCEPROP 2 LASTPIN (-4425 3825) $PN T73
J 0
(-4415 3835);
DISPLAY 0.617021 (-4415 3835);
PAINT ORANGE (-4415 3835);
FORCEPROP 2 LASTPIN (-4425 3775) $PN T77
J 0
(-4415 3785);
DISPLAY 0.617021 (-4415 3785);
PAINT ORANGE (-4415 3785);
FORCEPROP 2 LASTPIN (-4425 3725) $PN T83
J 0
(-4415 3735);
DISPLAY 0.617021 (-4415 3735);
PAINT ORANGE (-4415 3735);
FORCEPROP 2 LASTPIN (-4425 3675) $PN T85
J 0
(-4415 3685);
DISPLAY 0.617021 (-4415 3685);
PAINT ORANGE (-4415 3685);
FORCEPROP 2 LASTPIN (-4425 3625) $PN U2
J 0
(-4415 3635);
DISPLAY 0.617021 (-4415 3635);
PAINT ORANGE (-4415 3635);
FORCEPROP 2 LASTPIN (-4425 3575) $PN U4
J 0
(-4415 3585);
DISPLAY 0.617021 (-4415 3585);
PAINT ORANGE (-4415 3585);
FORCEPROP 2 LASTPIN (-4425 3525) $PN U6
J 0
(-4415 3535);
DISPLAY 0.617021 (-4415 3535);
PAINT ORANGE (-4415 3535);
FORCEPROP 2 LASTPIN (-4425 3475) $PN U20
J 0
(-4415 3485);
DISPLAY 0.617021 (-4415 3485);
PAINT ORANGE (-4415 3485);
FORCEPROP 2 LASTPIN (-4425 3425) $PN U22
J 0
(-4415 3435);
DISPLAY 0.617021 (-4415 3435);
PAINT ORANGE (-4415 3435);
FORCEPROP 2 LASTPIN (-4425 3375) $PN U24
J 0
(-4415 3385);
DISPLAY 0.617021 (-4415 3385);
PAINT ORANGE (-4415 3385);
FORCEPROP 2 LASTPIN (-4425 3325) $PN U30
J 0
(-4415 3335);
DISPLAY 0.617021 (-4415 3335);
PAINT ORANGE (-4415 3335);
FORCEPROP 2 LASTPIN (-4425 3275) $PN U36
J 0
(-4415 3285);
DISPLAY 0.617021 (-4415 3285);
PAINT ORANGE (-4415 3285);
FORCEPROP 2 LASTPIN (-4425 3225) $PN U42
J 0
(-4415 3235);
DISPLAY 0.617021 (-4415 3235);
PAINT ORANGE (-4415 3235);
FORCEPROP 2 LASTPIN (-4425 3175) $PN U68
J 0
(-4415 3185);
DISPLAY 0.617021 (-4415 3185);
PAINT ORANGE (-4415 3185);
FORCEPROP 2 LASTPIN (-4425 3125) $PN U70
J 0
(-4415 3135);
DISPLAY 0.617021 (-4415 3135);
PAINT ORANGE (-4415 3135);
FORCEPROP 2 LASTPIN (-4425 3075) $PN U74
J 0
(-4415 3085);
DISPLAY 0.617021 (-4415 3085);
PAINT ORANGE (-4415 3085);
FORCEPROP 2 LASTPIN (-4425 3025) $PN U76
J 0
(-4415 3035);
DISPLAY 0.617021 (-4415 3035);
PAINT ORANGE (-4415 3035);
FORCEPROP 2 LASTPIN (-4425 2975) $PN U78
J 0
(-4415 2985);
DISPLAY 0.617021 (-4415 2985);
PAINT ORANGE (-4415 2985);
FORCEPROP 2 LASTPIN (-4425 2925) $PN U80
J 0
(-4415 2935);
DISPLAY 0.617021 (-4415 2935);
PAINT ORANGE (-4415 2935);
FORCEPROP 2 LASTPIN (-4425 2875) $PN U86
J 0
(-4415 2885);
DISPLAY 0.617021 (-4415 2885);
PAINT ORANGE (-4415 2885);
FORCEPROP 2 LASTPIN (-4425 2825) $PN V1
J 0
(-4415 2835);
DISPLAY 0.617021 (-4415 2835);
PAINT ORANGE (-4415 2835);
FORCEPROP 2 LASTPIN (-4425 2775) $PN V5
J 0
(-4415 2785);
DISPLAY 0.617021 (-4415 2785);
PAINT ORANGE (-4415 2785);
FORCEPROP 2 LASTPIN (-4425 2725) $PN V9
J 0
(-4415 2735);
DISPLAY 0.617021 (-4415 2735);
PAINT ORANGE (-4415 2735);
FORCEPROP 2 LASTPIN (-4425 2675) $PN V13
J 0
(-4415 2685);
DISPLAY 0.617021 (-4415 2685);
PAINT ORANGE (-4415 2685);
FORCEPROP 2 LASTPIN (-4425 2625) $PN V15
J 0
(-4415 2635);
DISPLAY 0.617021 (-4415 2635);
PAINT ORANGE (-4415 2635);
FORCEPROP 2 LASTPIN (-4425 2575) $PN V21
J 0
(-4415 2585);
DISPLAY 0.617021 (-4415 2585);
PAINT ORANGE (-4415 2585);
FORCEPROP 2 LASTPIN (-4425 2525) $PN V23
J 0
(-4415 2535);
DISPLAY 0.617021 (-4415 2535);
PAINT ORANGE (-4415 2535);
FORCEPROP 2 LASTPIN (-4425 2475) $PN V43
J 0
(-4415 2485);
DISPLAY 0.617021 (-4415 2485);
PAINT ORANGE (-4415 2485);
FORCEPROP 2 LASTPIN (-4425 2425) $PN V73
J 0
(-4415 2435);
DISPLAY 0.617021 (-4415 2435);
PAINT ORANGE (-4415 2435);
FORCEPROP 2 LASTPIN (-4425 2375) $PN V75
J 0
(-4415 2385);
DISPLAY 0.617021 (-4415 2385);
PAINT ORANGE (-4415 2385);
FORCEPROP 2 LASTPIN (-4425 2325) $PN V77
J 0
(-4415 2335);
DISPLAY 0.617021 (-4415 2335);
PAINT ORANGE (-4415 2335);
FORCEPROP 2 LASTPIN (-4425 2275) $PN V83
J 0
(-4415 2285);
DISPLAY 0.617021 (-4415 2285);
PAINT ORANGE (-4415 2285);
FORCEPROP 2 LASTPIN (-4425 2225) $PN W8
J 0
(-4415 2235);
DISPLAY 0.617021 (-4415 2235);
PAINT ORANGE (-4415 2235);
FORCEPROP 2 LASTPIN (-4425 2175) $PN AC56
J 0
(-4415 2185);
DISPLAY 0.617021 (-4415 2185);
PAINT ORANGE (-4415 2185);
FORCEPROP 2 LASTPIN (-4425 2125) $PN W12
J 0
(-4415 2135);
DISPLAY 0.617021 (-4415 2135);
PAINT ORANGE (-4415 2135);
FORCEPROP 2 LASTPIN (-4425 2075) $PN W22
J 0
(-4415 2085);
DISPLAY 0.617021 (-4415 2085);
PAINT ORANGE (-4415 2085);
FORCEPROP 2 LASTPIN (-4425 2025) $PN W24
J 0
(-4415 2035);
DISPLAY 0.617021 (-4415 2035);
PAINT ORANGE (-4415 2035);
FORCEPROP 2 LASTPIN (-4425 1975) $PN W26
J 0
(-4415 1985);
DISPLAY 0.617021 (-4415 1985);
PAINT ORANGE (-4415 1985);
FORCEPROP 2 LASTPIN (-4425 1925) $PN W28
J 0
(-4415 1935);
DISPLAY 0.617021 (-4415 1935);
PAINT ORANGE (-4415 1935);
FORCEPROP 2 LASTPIN (-4425 1875) $PN W30
J 0
(-4415 1885);
DISPLAY 0.617021 (-4415 1885);
PAINT ORANGE (-4415 1885);
FORCEPROP 2 LASTPIN (-4425 1825) $PN W32
J 0
(-4415 1835);
DISPLAY 0.617021 (-4415 1835);
PAINT ORANGE (-4415 1835);
FORCEPROP 2 LASTPIN (-4425 1775) $PN W34
J 0
(-4415 1785);
DISPLAY 0.617021 (-4415 1785);
PAINT ORANGE (-4415 1785);
FORCEPROP 2 LASTPIN (-4425 1725) $PN W36
J 0
(-4415 1735);
DISPLAY 0.617021 (-4415 1735);
PAINT ORANGE (-4415 1735);
FORCEPROP 2 LASTPIN (-4425 1675) $PN W38
J 0
(-4415 1685);
DISPLAY 0.617021 (-4415 1685);
PAINT ORANGE (-4415 1685);
FORCEPROP 2 LASTPIN (-4425 1625) $PN W40
J 0
(-4415 1635);
DISPLAY 0.617021 (-4415 1635);
PAINT ORANGE (-4415 1635);
FORCEPROP 2 LASTPIN (-4425 1575) $PN W42
J 0
(-4415 1585);
DISPLAY 0.617021 (-4415 1585);
PAINT ORANGE (-4415 1585);
FORCEPROP 2 LASTPIN (-4425 1525) $PN W68
J 0
(-4415 1535);
DISPLAY 0.617021 (-4415 1535);
PAINT ORANGE (-4415 1535);
FORCEPROP 2 LASTPIN (-4425 1475) $PN W74
J 0
(-4415 1485);
DISPLAY 0.617021 (-4415 1485);
PAINT ORANGE (-4415 1485);
FORCEPROP 2 LASTPIN (-4425 1425) $PN W78
J 0
(-4415 1435);
DISPLAY 0.617021 (-4415 1435);
PAINT ORANGE (-4415 1435);
FORCEPROP 2 LASTPIN (-4425 1375) $PN W82
J 0
(-4415 1385);
DISPLAY 0.617021 (-4415 1385);
PAINT ORANGE (-4415 1385);
FORCEPROP 2 LASTPIN (-4425 1325) $PN Y15
J 0
(-4415 1335);
DISPLAY 0.617021 (-4415 1335);
PAINT ORANGE (-4415 1335);
FORCEPROP 2 LASTPIN (-4425 1275) $PN Y17
J 0
(-4415 1285);
DISPLAY 0.617021 (-4415 1285);
PAINT ORANGE (-4415 1285);
FORCEPROP 2 LASTPIN (-4425 1225) $PN Y5
J 0
(-4415 1235);
DISPLAY 0.617021 (-4415 1235);
PAINT ORANGE (-4415 1235);
FORCEPROP 2 LASTPIN (-4425 1175) $PN Y67
J 0
(-4415 1185);
DISPLAY 0.617021 (-4415 1185);
PAINT ORANGE (-4415 1185);
FORCEPROP 2 LASTPIN (-4425 1125) $PN Y7
J 0
(-4415 1135);
DISPLAY 0.617021 (-4415 1135);
PAINT ORANGE (-4415 1135);
FORCEPROP 2 LASTPIN (-4425 1075) $PN Y9
J 0
(-4415 1085);
DISPLAY 0.617021 (-4415 1085);
PAINT ORANGE (-4415 1085);
FORCEPROP 2 LASTPIN (-4425 1025) $PN Y71
J 0
(-4415 1035);
DISPLAY 0.617021 (-4415 1035);
PAINT ORANGE (-4415 1035);
FORCEPROP 2 LASTPIN (-4425 975) $PN Y73
J 0
(-4415 985);
DISPLAY 0.617021 (-4415 985);
PAINT ORANGE (-4415 985);
FORCEPROP 2 LASTPIN (-4425 925) $PN Y79
J 0
(-4415 935);
DISPLAY 0.617021 (-4415 935);
PAINT ORANGE (-4415 935);
FORCEPROP 2 LASTPIN (-4425 875) $PN Y81
J 0
(-4415 885);
DISPLAY 0.617021 (-4415 885);
PAINT ORANGE (-4415 885);
FORCEPROP 2 LASTPIN (-4425 825) $PN Y83
J 0
(-4415 835);
DISPLAY 0.617021 (-4415 835);
PAINT ORANGE (-4415 835);
FORCEPROP 2 LASTPIN (-4425 775) $PN Y85
J 0
(-4415 785);
DISPLAY 0.617021 (-4415 785);
PAINT ORANGE (-4415 785);
FORCEPROP 2 LASTPIN (-4425 725) $PN AA4
J 0
(-4415 735);
DISPLAY 0.617021 (-4415 735);
PAINT ORANGE (-4415 735);
FORCEPROP 2 LASTPIN (-4425 675) $PN AA16
J 0
(-4415 685);
DISPLAY 0.617021 (-4415 685);
PAINT ORANGE (-4415 685);
FORCEPROP 1 LAST PACK_TYPE BGA1
J 0
(-5575 4925);
PAINT SKYBLUE (-5575 4925);
DISPLAY INVISIBLE (-5575 4925);
FORCEPROP 2 LAST SEC_TYPE BGA1
J 0
(-5575 4925);
DISPLAY 1.021277 (-5575 4925);
PAINT ORANGE (-5575 4925);
DISPLAY INVISIBLE (-5575 4925);
FORCEPROP 2 LAST CDS_LIB chpset_lib
J 0
(-5025 2625);
PAINT ORANGE (-5025 2625);
DISPLAY INVISIBLE (-5025 2625);
FORCEPROP 2 LAST SEC 24
J 0
(-5575 4925);
DISPLAY 0.680851 (-5575 4925);
PAINT MONO (-5575 4925);
DISPLAY INVISIBLE (-5575 4925);
FORCEPROP 2 LAST CDS_LOCATION U2D1
J 0
(-5575 4875);
DISPLAY 0.617021 (-5575 4875);
PAINT AQUA (-5575 4875);
DISPLAY INVISIBLE (-5575 4875);
FORCEPROP 1 LAST PATH I21
J 0
(-5025 4825);
PAINT GREEN (-5025 4825);
DISPLAY INVISIBLE (-5025 4825);
FORCEADD SKX_EXT_B..25
(-3200 2625);
FORCEPROP 1 LAST LOCATION U2D1
J 0
(-3750 4875);
DISPLAY 0.617021 (-3750 4875);
PAINT AQUA (-3750 4875);
FORCEPROP 1 LAST PART_NUMBER TBD
J 0
(-3750 475);
DISPLAY 0.617021 (-3750 475);
PAINT BLUE (-3750 475);
FORCEPROP 1 LAST MATERIAL IC
J 0
(-3750 4825);
DISPLAY 0.617021 (-3750 4825);
PAINT SKYBLUE (-3750 4825);
FORCEPROP 2 LASTPIN (-3800 4625) $PN AA18
J 2
(-3810 4635);
DISPLAY 0.617021 (-3810 4635);
PAINT ORANGE (-3810 4635);
FORCEPROP 2 LASTPIN (-3800 4575) $PN AA22
J 2
(-3810 4585);
DISPLAY 0.617021 (-3810 4585);
PAINT ORANGE (-3810 4585);
FORCEPROP 2 LASTPIN (-3800 4525) $PN AA24
J 2
(-3810 4535);
DISPLAY 0.617021 (-3810 4535);
PAINT ORANGE (-3810 4535);
FORCEPROP 2 LASTPIN (-3800 4475) $PN AA30
J 2
(-3810 4485);
DISPLAY 0.617021 (-3810 4485);
PAINT ORANGE (-3810 4485);
FORCEPROP 2 LASTPIN (-3800 4425) $PN AA36
J 2
(-3810 4435);
DISPLAY 0.617021 (-3810 4435);
PAINT ORANGE (-3810 4435);
FORCEPROP 2 LASTPIN (-3800 4375) $PN AA42
J 2
(-3810 4385);
DISPLAY 0.617021 (-3810 4385);
PAINT ORANGE (-3810 4385);
FORCEPROP 2 LASTPIN (-3800 4325) $PN AA64
J 2
(-3810 4335);
DISPLAY 0.617021 (-3810 4335);
PAINT ORANGE (-3810 4335);
FORCEPROP 2 LASTPIN (-3800 4275) $PN AA66
J 2
(-3810 4285);
DISPLAY 0.617021 (-3810 4285);
PAINT ORANGE (-3810 4285);
FORCEPROP 2 LASTPIN (-3800 4225) $PN AA68
J 2
(-3810 4235);
DISPLAY 0.617021 (-3810 4235);
PAINT ORANGE (-3810 4235);
FORCEPROP 2 LASTPIN (-3800 4175) $PN AA76
J 2
(-3810 4185);
DISPLAY 0.617021 (-3810 4185);
PAINT ORANGE (-3810 4185);
FORCEPROP 2 LASTPIN (-3800 4125) $PN AA78
J 2
(-3810 4135);
DISPLAY 0.617021 (-3810 4135);
PAINT ORANGE (-3810 4135);
FORCEPROP 2 LASTPIN (-3800 4075) $PN AA80
J 2
(-3810 4085);
DISPLAY 0.617021 (-3810 4085);
PAINT ORANGE (-3810 4085);
FORCEPROP 2 LASTPIN (-3800 4025) $PN AA82
J 2
(-3810 4035);
DISPLAY 0.617021 (-3810 4035);
PAINT ORANGE (-3810 4035);
FORCEPROP 2 LASTPIN (-3800 3975) $PN AB1
J 2
(-3810 3985);
DISPLAY 0.617021 (-3810 3985);
PAINT ORANGE (-3810 3985);
FORCEPROP 2 LASTPIN (-3800 3925) $PN AB5
J 2
(-3810 3935);
DISPLAY 0.617021 (-3810 3935);
PAINT ORANGE (-3810 3935);
FORCEPROP 2 LASTPIN (-3800 3875) $PN AB11
J 2
(-3810 3885);
DISPLAY 0.617021 (-3810 3885);
PAINT ORANGE (-3810 3885);
FORCEPROP 2 LASTPIN (-3800 3825) $PN AB21
J 2
(-3810 3835);
DISPLAY 0.617021 (-3810 3835);
PAINT ORANGE (-3810 3835);
FORCEPROP 2 LASTPIN (-3800 3775) $PN AB23
J 2
(-3810 3785);
DISPLAY 0.617021 (-3810 3785);
PAINT ORANGE (-3810 3785);
FORCEPROP 2 LASTPIN (-3800 3725) $PN AB25
J 2
(-3810 3735);
DISPLAY 0.617021 (-3810 3735);
PAINT ORANGE (-3810 3735);
FORCEPROP 2 LASTPIN (-3800 3675) $PN AB29
J 2
(-3810 3685);
DISPLAY 0.617021 (-3810 3685);
PAINT ORANGE (-3810 3685);
FORCEPROP 2 LASTPIN (-3800 3625) $PN AB31
J 2
(-3810 3635);
DISPLAY 0.617021 (-3810 3635);
PAINT ORANGE (-3810 3635);
FORCEPROP 2 LASTPIN (-3800 3575) $PN AB35
J 2
(-3810 3585);
DISPLAY 0.617021 (-3810 3585);
PAINT ORANGE (-3810 3585);
FORCEPROP 2 LASTPIN (-3800 3525) $PN AB37
J 2
(-3810 3535);
DISPLAY 0.617021 (-3810 3535);
PAINT ORANGE (-3810 3535);
FORCEPROP 2 LASTPIN (-3800 3475) $PN AB41
J 2
(-3810 3485);
DISPLAY 0.617021 (-3810 3485);
PAINT ORANGE (-3810 3485);
FORCEPROP 2 LASTPIN (-3800 3425) $PN AB65
J 2
(-3810 3435);
DISPLAY 0.617021 (-3810 3435);
PAINT ORANGE (-3810 3435);
FORCEPROP 2 LASTPIN (-3800 3375) $PN AB69
J 2
(-3810 3385);
DISPLAY 0.617021 (-3810 3385);
PAINT ORANGE (-3810 3385);
FORCEPROP 2 LASTPIN (-3800 3325) $PN AB73
J 2
(-3810 3335);
DISPLAY 0.617021 (-3810 3335);
PAINT ORANGE (-3810 3335);
FORCEPROP 2 LASTPIN (-3800 3275) $PN AB79
J 2
(-3810 3285);
DISPLAY 0.617021 (-3810 3285);
PAINT ORANGE (-3810 3285);
FORCEPROP 2 LASTPIN (-3800 3225) $PN AB83
J 2
(-3810 3235);
DISPLAY 0.617021 (-3810 3235);
PAINT ORANGE (-3810 3235);
FORCEPROP 2 LASTPIN (-3800 3175) $PN AB85
J 2
(-3810 3185);
DISPLAY 0.617021 (-3810 3185);
PAINT ORANGE (-3810 3185);
FORCEPROP 2 LASTPIN (-3800 3125) $PN AC18
J 2
(-3810 3135);
DISPLAY 0.617021 (-3810 3135);
PAINT ORANGE (-3810 3135);
FORCEPROP 2 LASTPIN (-3800 3075) $PN AC22
J 2
(-3810 3085);
DISPLAY 0.617021 (-3810 3085);
PAINT ORANGE (-3810 3085);
FORCEPROP 2 LASTPIN (-3800 3025) $PN AC26
J 2
(-3810 3035);
DISPLAY 0.617021 (-3810 3035);
PAINT ORANGE (-3810 3035);
FORCEPROP 2 LASTPIN (-3800 2975) $PN AC28
J 2
(-3810 2985);
DISPLAY 0.617021 (-3810 2985);
PAINT ORANGE (-3810 2985);
FORCEPROP 2 LASTPIN (-3800 2925) $PN AC32
J 2
(-3810 2935);
DISPLAY 0.617021 (-3810 2935);
PAINT ORANGE (-3810 2935);
FORCEPROP 2 LASTPIN (-3800 2875) $PN AC34
J 2
(-3810 2885);
DISPLAY 0.617021 (-3810 2885);
PAINT ORANGE (-3810 2885);
FORCEPROP 2 LASTPIN (-3800 2825) $PN AC38
J 2
(-3810 2835);
DISPLAY 0.617021 (-3810 2835);
PAINT ORANGE (-3810 2835);
FORCEPROP 2 LASTPIN (-3800 2775) $PN AC40
J 2
(-3810 2785);
DISPLAY 0.617021 (-3810 2785);
PAINT ORANGE (-3810 2785);
FORCEPROP 2 LASTPIN (-3800 2725) $PN AC64
J 2
(-3810 2735);
DISPLAY 0.617021 (-3810 2735);
PAINT ORANGE (-3810 2735);
FORCEPROP 2 LASTPIN (-3800 2675) $PN AC70
J 2
(-3810 2685);
DISPLAY 0.617021 (-3810 2685);
PAINT ORANGE (-3810 2685);
FORCEPROP 2 LASTPIN (-3800 2625) $PN AC72
J 2
(-3810 2635);
DISPLAY 0.617021 (-3810 2635);
PAINT ORANGE (-3810 2635);
FORCEPROP 2 LASTPIN (-3800 2575) $PN AC78
J 2
(-3810 2585);
DISPLAY 0.617021 (-3810 2585);
PAINT ORANGE (-3810 2585);
FORCEPROP 2 LASTPIN (-3800 2525) $PN AC84
J 2
(-3810 2535);
DISPLAY 0.617021 (-3810 2535);
PAINT ORANGE (-3810 2535);
FORCEPROP 2 LASTPIN (-3800 2475) $PN AC86
J 2
(-3810 2485);
DISPLAY 0.617021 (-3810 2485);
PAINT ORANGE (-3810 2485);
FORCEPROP 2 LASTPIN (-3800 2425) $PN AD3
J 2
(-3810 2435);
DISPLAY 0.617021 (-3810 2435);
PAINT ORANGE (-3810 2435);
FORCEPROP 2 LASTPIN (-3800 2375) $PN AD7
J 2
(-3810 2385);
DISPLAY 0.617021 (-3810 2385);
PAINT ORANGE (-3810 2385);
FORCEPROP 2 LASTPIN (-3800 2325) $PN AD9
J 2
(-3810 2335);
DISPLAY 0.617021 (-3810 2335);
PAINT ORANGE (-3810 2335);
FORCEPROP 2 LASTPIN (-3800 2275) $PN AD11
J 2
(-3810 2285);
DISPLAY 0.617021 (-3810 2285);
PAINT ORANGE (-3810 2285);
FORCEPROP 2 LASTPIN (-3800 2225) $PN AD13
J 2
(-3810 2235);
DISPLAY 0.617021 (-3810 2235);
PAINT ORANGE (-3810 2235);
FORCEPROP 2 LASTPIN (-3800 2175) $PN AD15
J 2
(-3810 2185);
DISPLAY 0.617021 (-3810 2185);
PAINT ORANGE (-3810 2185);
FORCEPROP 2 LASTPIN (-3800 2125) $PN AD19
J 2
(-3810 2135);
DISPLAY 0.617021 (-3810 2135);
PAINT ORANGE (-3810 2135);
FORCEPROP 2 LASTPIN (-3800 2075) $PN AD21
J 2
(-3810 2085);
DISPLAY 0.617021 (-3810 2085);
PAINT ORANGE (-3810 2085);
FORCEPROP 2 LASTPIN (-3800 2025) $PN AD27
J 2
(-3810 2035);
DISPLAY 0.617021 (-3810 2035);
PAINT ORANGE (-3810 2035);
FORCEPROP 2 LASTPIN (-3800 1975) $PN AD33
J 2
(-3810 1985);
DISPLAY 0.617021 (-3810 1985);
PAINT ORANGE (-3810 1985);
FORCEPROP 2 LASTPIN (-3800 1925) $PN AD39
J 2
(-3810 1935);
DISPLAY 0.617021 (-3810 1935);
PAINT ORANGE (-3810 1935);
FORCEPROP 2 LASTPIN (-3800 1875) $PN AD43
J 2
(-3810 1885);
DISPLAY 0.617021 (-3810 1885);
PAINT ORANGE (-3810 1885);
FORCEPROP 2 LASTPIN (-3800 1825) $PN AD71
J 2
(-3810 1835);
DISPLAY 0.617021 (-3810 1835);
PAINT ORANGE (-3810 1835);
FORCEPROP 2 LASTPIN (-3800 1775) $PN AD73
J 2
(-3810 1785);
DISPLAY 0.617021 (-3810 1785);
PAINT ORANGE (-3810 1785);
FORCEPROP 2 LASTPIN (-3800 1725) $PN AD75
J 2
(-3810 1735);
DISPLAY 0.617021 (-3810 1735);
PAINT ORANGE (-3810 1735);
FORCEPROP 2 LASTPIN (-3800 1675) $PN AD81
J 2
(-3810 1685);
DISPLAY 0.617021 (-3810 1685);
PAINT ORANGE (-3810 1685);
FORCEPROP 2 LASTPIN (-3800 1625) $PN AD83
J 2
(-3810 1635);
DISPLAY 0.617021 (-3810 1635);
PAINT ORANGE (-3810 1635);
FORCEPROP 2 LASTPIN (-3800 1575) $PN AD85
J 2
(-3810 1585);
DISPLAY 0.617021 (-3810 1585);
PAINT ORANGE (-3810 1585);
FORCEPROP 2 LASTPIN (-3800 1525) $PN AE4
J 2
(-3810 1535);
DISPLAY 0.617021 (-3810 1535);
PAINT ORANGE (-3810 1535);
FORCEPROP 2 LASTPIN (-3800 1475) $PN AE8
J 2
(-3810 1485);
DISPLAY 0.617021 (-3810 1485);
PAINT ORANGE (-3810 1485);
FORCEPROP 2 LASTPIN (-3800 1425) $PN AC54
J 2
(-3810 1435);
DISPLAY 0.617021 (-3810 1435);
PAINT ORANGE (-3810 1435);
FORCEPROP 2 LASTPIN (-3800 1375) $PN AE16
J 2
(-3810 1385);
DISPLAY 0.617021 (-3810 1385);
PAINT ORANGE (-3810 1385);
FORCEPROP 2 LASTPIN (-3800 1325) $PN AE38
J 2
(-3810 1335);
DISPLAY 0.617021 (-3810 1335);
PAINT ORANGE (-3810 1335);
FORCEPROP 2 LASTPIN (-3800 1275) $PN AE40
J 2
(-3810 1285);
DISPLAY 0.617021 (-3810 1285);
PAINT ORANGE (-3810 1285);
FORCEPROP 2 LASTPIN (-3800 1225) $PN AE42
J 2
(-3810 1235);
DISPLAY 0.617021 (-3810 1235);
PAINT ORANGE (-3810 1235);
FORCEPROP 2 LASTPIN (-3800 1175) $PN AE64
J 2
(-3810 1185);
DISPLAY 0.617021 (-3810 1185);
PAINT ORANGE (-3810 1185);
FORCEPROP 2 LASTPIN (-3800 1125) $PN AE66
J 2
(-3810 1135);
DISPLAY 0.617021 (-3810 1135);
PAINT ORANGE (-3810 1135);
FORCEPROP 2 LASTPIN (-3800 1075) $PN AE68
J 2
(-3810 1085);
DISPLAY 0.617021 (-3810 1085);
PAINT ORANGE (-3810 1085);
FORCEPROP 2 LASTPIN (-3800 1025) $PN AE70
J 2
(-3810 1035);
DISPLAY 0.617021 (-3810 1035);
PAINT ORANGE (-3810 1035);
FORCEPROP 2 LASTPIN (-3800 975) $PN AE78
J 2
(-3810 985);
DISPLAY 0.617021 (-3810 985);
PAINT ORANGE (-3810 985);
FORCEPROP 2 LASTPIN (-3800 925) $PN AF1
J 2
(-3810 935);
DISPLAY 0.617021 (-3810 935);
PAINT ORANGE (-3810 935);
FORCEPROP 2 LASTPIN (-3800 875) $PN AC52
J 2
(-3810 885);
DISPLAY 0.617021 (-3810 885);
PAINT ORANGE (-3810 885);
FORCEPROP 2 LASTPIN (-3800 825) $PN AF9
J 2
(-3810 835);
DISPLAY 0.617021 (-3810 835);
PAINT ORANGE (-3810 835);
FORCEPROP 2 LASTPIN (-3800 775) $PN AF21
J 2
(-3810 785);
DISPLAY 0.617021 (-3810 785);
PAINT ORANGE (-3810 785);
FORCEPROP 2 LASTPIN (-3800 725) $PN AF23
J 2
(-3810 735);
DISPLAY 0.617021 (-3810 735);
PAINT ORANGE (-3810 735);
FORCEPROP 2 LASTPIN (-3800 675) $PN AF25
J 2
(-3810 685);
DISPLAY 0.617021 (-3810 685);
PAINT ORANGE (-3810 685);
FORCEPROP 2 LASTPIN (-2600 4625) $PN AF27
J 0
(-2590 4635);
DISPLAY 0.617021 (-2590 4635);
PAINT ORANGE (-2590 4635);
FORCEPROP 2 LASTPIN (-2600 4575) $PN AF29
J 0
(-2590 4585);
DISPLAY 0.617021 (-2590 4585);
PAINT ORANGE (-2590 4585);
FORCEPROP 2 LASTPIN (-2600 4525) $PN AF31
J 0
(-2590 4535);
DISPLAY 0.617021 (-2590 4535);
PAINT ORANGE (-2590 4535);
FORCEPROP 2 LASTPIN (-2600 4475) $PN AF33
J 0
(-2590 4485);
DISPLAY 0.617021 (-2590 4485);
PAINT ORANGE (-2590 4485);
FORCEPROP 2 LASTPIN (-2600 4425) $PN AF37
J 0
(-2590 4435);
DISPLAY 0.617021 (-2590 4435);
PAINT ORANGE (-2590 4435);
FORCEPROP 2 LASTPIN (-2600 4375) $PN AF39
J 0
(-2590 4385);
DISPLAY 0.617021 (-2590 4385);
PAINT ORANGE (-2590 4385);
FORCEPROP 2 LASTPIN (-2600 4325) $PN AF41
J 0
(-2590 4335);
DISPLAY 0.617021 (-2590 4335);
PAINT ORANGE (-2590 4335);
FORCEPROP 2 LASTPIN (-2600 4275) $PN AF73
J 0
(-2590 4285);
DISPLAY 0.617021 (-2590 4285);
PAINT ORANGE (-2590 4285);
FORCEPROP 2 LASTPIN (-2600 4225) $PN AF77
J 0
(-2590 4235);
DISPLAY 0.617021 (-2590 4235);
PAINT ORANGE (-2590 4235);
FORCEPROP 2 LASTPIN (-2600 4175) $PN AF83
J 0
(-2590 4185);
DISPLAY 0.617021 (-2590 4185);
PAINT ORANGE (-2590 4185);
FORCEPROP 2 LASTPIN (-2600 4125) $PN AF85
J 0
(-2590 4135);
DISPLAY 0.617021 (-2590 4135);
PAINT ORANGE (-2590 4135);
FORCEPROP 2 LASTPIN (-2600 4075) $PN AG12
J 0
(-2590 4085);
DISPLAY 0.617021 (-2590 4085);
PAINT ORANGE (-2590 4085);
FORCEPROP 2 LASTPIN (-2600 4025) $PN AG14
J 0
(-2590 4035);
DISPLAY 0.617021 (-2590 4035);
PAINT ORANGE (-2590 4035);
FORCEPROP 2 LASTPIN (-2600 3975) $PN AG18
J 0
(-2590 3985);
DISPLAY 0.617021 (-2590 3985);
PAINT ORANGE (-2590 3985);
FORCEPROP 2 LASTPIN (-2600 3925) $PN AG36
J 0
(-2590 3935);
DISPLAY 0.617021 (-2590 3935);
PAINT ORANGE (-2590 3935);
FORCEPROP 2 LASTPIN (-2600 3875) $PN AG64
J 0
(-2590 3885);
DISPLAY 0.617021 (-2590 3885);
PAINT ORANGE (-2590 3885);
FORCEPROP 2 LASTPIN (-2600 3825) $PN AG70
J 0
(-2590 3835);
DISPLAY 0.617021 (-2590 3835);
PAINT ORANGE (-2590 3835);
FORCEPROP 2 LASTPIN (-2600 3775) $PN AG74
J 0
(-2590 3785);
DISPLAY 0.617021 (-2590 3785);
PAINT ORANGE (-2590 3785);
FORCEPROP 2 LASTPIN (-2600 3725) $PN AG76
J 0
(-2590 3735);
DISPLAY 0.617021 (-2590 3735);
PAINT ORANGE (-2590 3735);
FORCEPROP 2 LASTPIN (-2600 3675) $PN AG78
J 0
(-2590 3685);
DISPLAY 0.617021 (-2590 3685);
PAINT ORANGE (-2590 3685);
FORCEPROP 2 LASTPIN (-2600 3625) $PN AG80
J 0
(-2590 3635);
DISPLAY 0.617021 (-2590 3635);
PAINT ORANGE (-2590 3635);
FORCEPROP 2 LASTPIN (-2600 3575) $PN AH1
J 0
(-2590 3585);
DISPLAY 0.617021 (-2590 3585);
PAINT ORANGE (-2590 3585);
FORCEPROP 2 LASTPIN (-2600 3525) $PN AH5
J 0
(-2590 3535);
DISPLAY 0.617021 (-2590 3535);
PAINT ORANGE (-2590 3535);
FORCEPROP 2 LASTPIN (-2600 3475) $PN AH21
J 0
(-2590 3485);
DISPLAY 0.617021 (-2590 3485);
PAINT ORANGE (-2590 3485);
FORCEPROP 2 LASTPIN (-2600 3425) $PN AH27
J 0
(-2590 3435);
DISPLAY 0.617021 (-2590 3435);
PAINT ORANGE (-2590 3435);
FORCEPROP 2 LASTPIN (-2600 3375) $PN AH33
J 0
(-2590 3385);
DISPLAY 0.617021 (-2590 3385);
PAINT ORANGE (-2590 3385);
FORCEPROP 2 LASTPIN (-2600 3325) $PN AH35
J 0
(-2590 3335);
DISPLAY 0.617021 (-2590 3335);
PAINT ORANGE (-2590 3335);
FORCEPROP 2 LASTPIN (-2600 3275) $PN AH45
J 0
(-2590 3285);
DISPLAY 0.617021 (-2590 3285);
PAINT ORANGE (-2590 3285);
FORCEPROP 2 LASTPIN (-2600 3225) $PN AH47
J 0
(-2590 3235);
DISPLAY 0.617021 (-2590 3235);
PAINT ORANGE (-2590 3235);
FORCEPROP 2 LASTPIN (-2600 3175) $PN AH49
J 0
(-2590 3185);
DISPLAY 0.617021 (-2590 3185);
PAINT ORANGE (-2590 3185);
FORCEPROP 2 LASTPIN (-2600 3125) $PN AH51
J 0
(-2590 3135);
DISPLAY 0.617021 (-2590 3135);
PAINT ORANGE (-2590 3135);
FORCEPROP 2 LASTPIN (-2600 3075) $PN AH53
J 0
(-2590 3085);
DISPLAY 0.617021 (-2590 3085);
PAINT ORANGE (-2590 3085);
FORCEPROP 2 LASTPIN (-2600 3025) $PN AH59
J 0
(-2590 3035);
DISPLAY 0.617021 (-2590 3035);
PAINT ORANGE (-2590 3035);
FORCEPROP 2 LASTPIN (-2600 2975) $PN AH61
J 0
(-2590 2985);
DISPLAY 0.617021 (-2590 2985);
PAINT ORANGE (-2590 2985);
FORCEPROP 2 LASTPIN (-2600 2925) $PN AH65
J 0
(-2590 2935);
DISPLAY 0.617021 (-2590 2935);
PAINT ORANGE (-2590 2935);
FORCEPROP 2 LASTPIN (-2600 2875) $PN AH69
J 0
(-2590 2885);
DISPLAY 0.617021 (-2590 2885);
PAINT ORANGE (-2590 2885);
FORCEPROP 2 LASTPIN (-2600 2825) $PN AH75
J 0
(-2590 2835);
DISPLAY 0.617021 (-2590 2835);
PAINT ORANGE (-2590 2835);
FORCEPROP 2 LASTPIN (-2600 2775) $PN AH77
J 0
(-2590 2785);
DISPLAY 0.617021 (-2590 2785);
PAINT ORANGE (-2590 2785);
FORCEPROP 2 LASTPIN (-2600 2725) $PN AH83
J 0
(-2590 2735);
DISPLAY 0.617021 (-2590 2735);
PAINT ORANGE (-2590 2735);
FORCEPROP 2 LASTPIN (-2600 2675) $PN AJ8
J 0
(-2590 2685);
DISPLAY 0.617021 (-2590 2685);
PAINT ORANGE (-2590 2685);
FORCEPROP 2 LASTPIN (-2600 2625) $PN AJ22
J 0
(-2590 2635);
DISPLAY 0.617021 (-2590 2635);
PAINT ORANGE (-2590 2635);
FORCEPROP 2 LASTPIN (-2600 2575) $PN AJ26
J 0
(-2590 2585);
DISPLAY 0.617021 (-2590 2585);
PAINT ORANGE (-2590 2585);
FORCEPROP 2 LASTPIN (-2600 2525) $PN AJ28
J 0
(-2590 2535);
DISPLAY 0.617021 (-2590 2535);
PAINT ORANGE (-2590 2535);
FORCEPROP 2 LASTPIN (-2600 2475) $PN AJ32
J 0
(-2590 2485);
DISPLAY 0.617021 (-2590 2485);
PAINT ORANGE (-2590 2485);
FORCEPROP 2 LASTPIN (-2600 2425) $PN AJ34
J 0
(-2590 2435);
DISPLAY 0.617021 (-2590 2435);
PAINT ORANGE (-2590 2435);
FORCEPROP 2 LASTPIN (-2600 2375) $PN AJ46
J 0
(-2590 2385);
DISPLAY 0.617021 (-2590 2385);
PAINT ORANGE (-2590 2385);
FORCEPROP 2 LASTPIN (-2600 2325) $PN AJ48
J 0
(-2590 2335);
DISPLAY 0.617021 (-2590 2335);
PAINT ORANGE (-2590 2335);
FORCEPROP 2 LASTPIN (-2600 2275) $PN AJ50
J 0
(-2590 2285);
DISPLAY 0.617021 (-2590 2285);
PAINT ORANGE (-2590 2285);
FORCEPROP 2 LASTPIN (-2600 2225) $PN AJ52
J 0
(-2590 2235);
DISPLAY 0.617021 (-2590 2235);
PAINT ORANGE (-2590 2235);
FORCEPROP 2 LASTPIN (-2600 2175) $PN AJ54
J 0
(-2590 2185);
DISPLAY 0.617021 (-2590 2185);
PAINT ORANGE (-2590 2185);
FORCEPROP 2 LASTPIN (-2600 2125) $PN AJ66
J 0
(-2590 2135);
DISPLAY 0.617021 (-2590 2135);
PAINT ORANGE (-2590 2135);
FORCEPROP 2 LASTPIN (-2600 2075) $PN AJ68
J 0
(-2590 2085);
DISPLAY 0.617021 (-2590 2085);
PAINT ORANGE (-2590 2085);
FORCEPROP 2 LASTPIN (-2600 2025) $PN AJ74
J 0
(-2590 2035);
DISPLAY 0.617021 (-2590 2035);
PAINT ORANGE (-2590 2035);
FORCEPROP 2 LASTPIN (-2600 1975) $PN AJ78
J 0
(-2590 1985);
DISPLAY 0.617021 (-2590 1985);
PAINT ORANGE (-2590 1985);
FORCEPROP 2 LASTPIN (-2600 1925) $PN AJ82
J 0
(-2590 1935);
DISPLAY 0.617021 (-2590 1935);
PAINT ORANGE (-2590 1935);
FORCEPROP 2 LASTPIN (-2600 1875) $PN AJ86
J 0
(-2590 1885);
DISPLAY 0.617021 (-2590 1885);
PAINT ORANGE (-2590 1885);
FORCEPROP 2 LASTPIN (-2600 1825) $PN AK9
J 0
(-2590 1835);
DISPLAY 0.617021 (-2590 1835);
PAINT ORANGE (-2590 1835);
FORCEPROP 2 LASTPIN (-2600 1775) $PN AK13
J 0
(-2590 1785);
DISPLAY 0.617021 (-2590 1785);
PAINT ORANGE (-2590 1785);
FORCEPROP 2 LASTPIN (-2600 1725) $PN AK19
J 0
(-2590 1735);
DISPLAY 0.617021 (-2590 1735);
PAINT ORANGE (-2590 1735);
FORCEPROP 2 LASTPIN (-2600 1675) $PN AK23
J 0
(-2590 1685);
DISPLAY 0.617021 (-2590 1685);
PAINT ORANGE (-2590 1685);
FORCEPROP 2 LASTPIN (-2600 1625) $PN AK25
J 0
(-2590 1635);
DISPLAY 0.617021 (-2590 1635);
PAINT ORANGE (-2590 1635);
FORCEPROP 2 LASTPIN (-2600 1575) $PN AK29
J 0
(-2590 1585);
DISPLAY 0.617021 (-2590 1585);
PAINT ORANGE (-2590 1585);
FORCEPROP 2 LASTPIN (-2600 1525) $PN AK31
J 0
(-2590 1535);
DISPLAY 0.617021 (-2590 1535);
PAINT ORANGE (-2590 1535);
FORCEPROP 2 LASTPIN (-2600 1475) $PN AK33
J 0
(-2590 1485);
DISPLAY 0.617021 (-2590 1485);
PAINT ORANGE (-2590 1485);
FORCEPROP 2 LASTPIN (-2600 1425) $PN AK55
J 0
(-2590 1435);
DISPLAY 0.617021 (-2590 1435);
PAINT ORANGE (-2590 1435);
FORCEPROP 2 LASTPIN (-2600 1375) $PN AK65
J 0
(-2590 1385);
DISPLAY 0.617021 (-2590 1385);
PAINT ORANGE (-2590 1385);
FORCEPROP 2 LASTPIN (-2600 1325) $PN AK67
J 0
(-2590 1335);
DISPLAY 0.617021 (-2590 1335);
PAINT ORANGE (-2590 1335);
FORCEPROP 2 LASTPIN (-2600 1275) $PN AK73
J 0
(-2590 1285);
DISPLAY 0.617021 (-2590 1285);
PAINT ORANGE (-2590 1285);
FORCEPROP 2 LASTPIN (-2600 1225) $PN AK79
J 0
(-2590 1235);
DISPLAY 0.617021 (-2590 1235);
PAINT ORANGE (-2590 1235);
FORCEPROP 2 LASTPIN (-2600 1175) $PN AK81
J 0
(-2590 1185);
DISPLAY 0.617021 (-2590 1185);
PAINT ORANGE (-2590 1185);
FORCEPROP 2 LASTPIN (-2600 1125) $PN AK83
J 0
(-2590 1135);
DISPLAY 0.617021 (-2590 1135);
PAINT ORANGE (-2590 1135);
FORCEPROP 2 LASTPIN (-2600 1075) $PN AK85
J 0
(-2590 1085);
DISPLAY 0.617021 (-2590 1085);
PAINT ORANGE (-2590 1085);
FORCEPROP 2 LASTPIN (-2600 1025) $PN AL4
J 0
(-2590 1035);
DISPLAY 0.617021 (-2590 1035);
PAINT ORANGE (-2590 1035);
FORCEPROP 2 LASTPIN (-2600 975) $PN AL10
J 0
(-2590 985);
DISPLAY 0.617021 (-2590 985);
PAINT ORANGE (-2590 985);
FORCEPROP 2 LASTPIN (-2600 925) $PN AL24
J 0
(-2590 935);
DISPLAY 0.617021 (-2590 935);
PAINT ORANGE (-2590 935);
FORCEPROP 2 LASTPIN (-2600 875) $PN AL30
J 0
(-2590 885);
DISPLAY 0.617021 (-2590 885);
PAINT ORANGE (-2590 885);
FORCEPROP 2 LASTPIN (-2600 825) $PN AL32
J 0
(-2590 835);
DISPLAY 0.617021 (-2590 835);
PAINT ORANGE (-2590 835);
FORCEPROP 2 LASTPIN (-2600 775) $PN AL56
J 0
(-2590 785);
DISPLAY 0.617021 (-2590 785);
PAINT ORANGE (-2590 785);
FORCEPROP 2 LASTPIN (-2600 725) $PN AL64
J 0
(-2590 735);
DISPLAY 0.617021 (-2590 735);
PAINT ORANGE (-2590 735);
FORCEPROP 2 LASTPIN (-2600 675) $PN AL68
J 0
(-2590 685);
DISPLAY 0.617021 (-2590 685);
PAINT ORANGE (-2590 685);
FORCEPROP 1 LAST PACK_TYPE BGA1
J 0
(-3750 4925);
PAINT SKYBLUE (-3750 4925);
DISPLAY INVISIBLE (-3750 4925);
FORCEPROP 2 LAST SEC_TYPE BGA1
J 0
(-3750 4925);
DISPLAY 1.021277 (-3750 4925);
PAINT ORANGE (-3750 4925);
DISPLAY INVISIBLE (-3750 4925);
FORCEPROP 2 LAST CDS_LIB chpset_lib
J 0
(-3200 2625);
PAINT ORANGE (-3200 2625);
DISPLAY INVISIBLE (-3200 2625);
FORCEPROP 2 LAST SEC 25
J 0
(-3750 4925);
DISPLAY 0.680851 (-3750 4925);
PAINT MONO (-3750 4925);
DISPLAY INVISIBLE (-3750 4925);
FORCEPROP 2 LAST CDS_LOCATION U2D1
J 0
(-3750 4875);
DISPLAY 0.617021 (-3750 4875);
PAINT AQUA (-3750 4875);
DISPLAY INVISIBLE (-3750 4875);
FORCEPROP 1 LAST PATH I22
J 0
(-3200 4825);
PAINT GREEN (-3200 4825);
DISPLAY INVISIBLE (-3200 4825);
FORCEADD SKX_EXT_B..26
(-1275 2600);
FORCEPROP 1 LAST LOCATION U2D1
J 0
(-1825 4850);
DISPLAY 0.617021 (-1825 4850);
PAINT AQUA (-1825 4850);
FORCEPROP 1 LAST PART_NUMBER TBD
J 0
(-1825 450);
DISPLAY 0.617021 (-1825 450);
PAINT BLUE (-1825 450);
FORCEPROP 1 LAST MATERIAL IC
J 0
(-1825 4800);
DISPLAY 0.617021 (-1825 4800);
PAINT SKYBLUE (-1825 4800);
FORCEPROP 2 LASTPIN (-1875 4600) $PN AL76
J 2
(-1885 4610);
DISPLAY 0.617021 (-1885 4610);
PAINT ORANGE (-1885 4610);
FORCEPROP 2 LASTPIN (-1875 4550) $PN AL78
J 2
(-1885 4560);
DISPLAY 0.617021 (-1885 4560);
PAINT ORANGE (-1885 4560);
FORCEPROP 2 LASTPIN (-1875 4500) $PN AL80
J 2
(-1885 4510);
DISPLAY 0.617021 (-1885 4510);
PAINT ORANGE (-1885 4510);
FORCEPROP 2 LASTPIN (-1875 4450) $PN AL82
J 2
(-1885 4460);
DISPLAY 0.617021 (-1885 4460);
PAINT ORANGE (-1885 4460);
FORCEPROP 2 LASTPIN (-1875 4400) $PN AL86
J 2
(-1885 4410);
DISPLAY 0.617021 (-1885 4410);
PAINT ORANGE (-1885 4410);
FORCEPROP 2 LASTPIN (-1875 4350) $PN AM1
J 2
(-1885 4360);
DISPLAY 0.617021 (-1885 4360);
PAINT ORANGE (-1885 4360);
FORCEPROP 2 LASTPIN (-1875 4300) $PN AC50
J 2
(-1885 4310);
DISPLAY 0.617021 (-1885 4310);
PAINT ORANGE (-1885 4310);
FORCEPROP 2 LASTPIN (-1875 4250) $PN AM31
J 2
(-1885 4260);
DISPLAY 0.617021 (-1885 4260);
PAINT ORANGE (-1885 4260);
FORCEPROP 2 LASTPIN (-1875 4200) $PN AM57
J 2
(-1885 4210);
DISPLAY 0.617021 (-1885 4210);
PAINT ORANGE (-1885 4210);
FORCEPROP 2 LASTPIN (-1875 4150) $PN AM63
J 2
(-1885 4160);
DISPLAY 0.617021 (-1885 4160);
PAINT ORANGE (-1885 4160);
FORCEPROP 2 LASTPIN (-1875 4100) $PN AM69
J 2
(-1885 4110);
DISPLAY 0.617021 (-1885 4110);
PAINT ORANGE (-1885 4110);
FORCEPROP 2 LASTPIN (-1875 4050) $PN AM73
J 2
(-1885 4060);
DISPLAY 0.617021 (-1885 4060);
PAINT ORANGE (-1885 4060);
FORCEPROP 2 LASTPIN (-1875 4000) $PN AM79
J 2
(-1885 4010);
DISPLAY 0.617021 (-1885 4010);
PAINT ORANGE (-1885 4010);
FORCEPROP 2 LASTPIN (-1875 3950) $PN AM83
J 2
(-1885 3960);
DISPLAY 0.617021 (-1885 3960);
PAINT ORANGE (-1885 3960);
FORCEPROP 2 LASTPIN (-1875 3900) $PN AN2
J 2
(-1885 3910);
DISPLAY 0.617021 (-1885 3910);
PAINT ORANGE (-1885 3910);
FORCEPROP 2 LASTPIN (-1875 3850) $PN AN6
J 2
(-1885 3860);
DISPLAY 0.617021 (-1885 3860);
PAINT ORANGE (-1885 3860);
FORCEPROP 2 LASTPIN (-1875 3800) $PN AN28
J 2
(-1885 3810);
DISPLAY 0.617021 (-1885 3810);
PAINT ORANGE (-1885 3810);
FORCEPROP 2 LASTPIN (-1875 3750) $PN AN58
J 2
(-1885 3760);
DISPLAY 0.617021 (-1885 3760);
PAINT ORANGE (-1885 3760);
FORCEPROP 2 LASTPIN (-1875 3700) $PN AN78
J 2
(-1885 3710);
DISPLAY 0.617021 (-1885 3710);
PAINT ORANGE (-1885 3710);
FORCEPROP 2 LASTPIN (-1875 3650) $PN AP5
J 2
(-1885 3660);
DISPLAY 0.617021 (-1885 3660);
PAINT ORANGE (-1885 3660);
FORCEPROP 2 LASTPIN (-1875 3600) $PN AP9
J 2
(-1885 3610);
DISPLAY 0.617021 (-1885 3610);
PAINT ORANGE (-1885 3610);
FORCEPROP 2 LASTPIN (-1875 3550) $PN AP13
J 2
(-1885 3560);
DISPLAY 0.617021 (-1885 3560);
PAINT ORANGE (-1885 3560);
FORCEPROP 2 LASTPIN (-1875 3500) $PN AP19
J 2
(-1885 3510);
DISPLAY 0.617021 (-1885 3510);
PAINT ORANGE (-1885 3510);
FORCEPROP 2 LASTPIN (-1875 3450) $PN AP31
J 2
(-1885 3460);
DISPLAY 0.617021 (-1885 3460);
PAINT ORANGE (-1885 3460);
FORCEPROP 2 LASTPIN (-1875 3400) $PN AP59
J 2
(-1885 3410);
DISPLAY 0.617021 (-1885 3410);
PAINT ORANGE (-1885 3410);
FORCEPROP 2 LASTPIN (-1875 3350) $PN AP63
J 2
(-1885 3360);
DISPLAY 0.617021 (-1885 3360);
PAINT ORANGE (-1885 3360);
FORCEPROP 2 LASTPIN (-1875 3300) $PN AP65
J 2
(-1885 3310);
DISPLAY 0.617021 (-1885 3310);
PAINT ORANGE (-1885 3310);
FORCEPROP 2 LASTPIN (-1875 3250) $PN AP67
J 2
(-1885 3260);
DISPLAY 0.617021 (-1885 3260);
PAINT ORANGE (-1885 3260);
FORCEPROP 2 LASTPIN (-1875 3200) $PN AP69
J 2
(-1885 3210);
DISPLAY 0.617021 (-1885 3210);
PAINT ORANGE (-1885 3210);
FORCEPROP 2 LASTPIN (-1875 3150) $PN AP73
J 2
(-1885 3160);
DISPLAY 0.617021 (-1885 3160);
PAINT ORANGE (-1885 3160);
FORCEPROP 2 LASTPIN (-1875 3100) $PN AP75
J 2
(-1885 3110);
DISPLAY 0.617021 (-1885 3110);
PAINT ORANGE (-1885 3110);
FORCEPROP 2 LASTPIN (-1875 3050) $PN AP81
J 2
(-1885 3060);
DISPLAY 0.617021 (-1885 3060);
PAINT ORANGE (-1885 3060);
FORCEPROP 2 LASTPIN (-1875 3000) $PN AP83
J 2
(-1885 3010);
DISPLAY 0.617021 (-1885 3010);
PAINT ORANGE (-1885 3010);
FORCEPROP 2 LASTPIN (-1875 2950) $PN AP85
J 2
(-1885 2960);
DISPLAY 0.617021 (-1885 2960);
PAINT ORANGE (-1885 2960);
FORCEPROP 2 LASTPIN (-1875 2900) $PN AR10
J 2
(-1885 2910);
DISPLAY 0.617021 (-1885 2910);
PAINT ORANGE (-1885 2910);
FORCEPROP 2 LASTPIN (-1875 2850) $PN AR24
J 2
(-1885 2860);
DISPLAY 0.617021 (-1885 2860);
PAINT ORANGE (-1885 2860);
FORCEPROP 2 LASTPIN (-1875 2800) $PN AR30
J 2
(-1885 2810);
DISPLAY 0.617021 (-1885 2810);
PAINT ORANGE (-1885 2810);
FORCEPROP 2 LASTPIN (-1875 2750) $PN AR60
J 2
(-1885 2760);
DISPLAY 0.617021 (-1885 2760);
PAINT ORANGE (-1885 2760);
FORCEPROP 2 LASTPIN (-1875 2700) $PN AR72
J 2
(-1885 2710);
DISPLAY 0.617021 (-1885 2710);
PAINT ORANGE (-1885 2710);
FORCEPROP 2 LASTPIN (-1875 2650) $PN AR78
J 2
(-1885 2660);
DISPLAY 0.617021 (-1885 2660);
PAINT ORANGE (-1885 2660);
FORCEPROP 2 LASTPIN (-1875 2600) $PN AC48
J 2
(-1885 2610);
DISPLAY 0.617021 (-1885 2610);
PAINT ORANGE (-1885 2610);
FORCEPROP 2 LASTPIN (-1875 2550) $PN P63
J 2
(-1885 2560);
DISPLAY 0.617021 (-1885 2560);
PAINT ORANGE (-1885 2560);
FORCEPROP 2 LASTPIN (-1875 2500) $PN AT15
J 2
(-1885 2510);
DISPLAY 0.617021 (-1885 2510);
PAINT ORANGE (-1885 2510);
FORCEPROP 2 LASTPIN (-1875 2450) $PN AT17
J 2
(-1885 2460);
DISPLAY 0.617021 (-1885 2460);
PAINT ORANGE (-1885 2460);
FORCEPROP 2 LASTPIN (-1875 2400) $PN AT21
J 2
(-1885 2410);
DISPLAY 0.617021 (-1885 2410);
PAINT ORANGE (-1885 2410);
FORCEPROP 2 LASTPIN (-1875 2350) $PN AT27
J 2
(-1885 2360);
DISPLAY 0.617021 (-1885 2360);
PAINT ORANGE (-1885 2360);
FORCEPROP 2 LASTPIN (-1875 2300) $PN AT61
J 2
(-1885 2310);
DISPLAY 0.617021 (-1885 2310);
PAINT ORANGE (-1885 2310);
FORCEPROP 2 LASTPIN (-1875 2250) $PN AT63
J 2
(-1885 2260);
DISPLAY 0.617021 (-1885 2260);
PAINT ORANGE (-1885 2260);
FORCEPROP 2 LASTPIN (-1875 2200) $PN AT69
J 2
(-1885 2210);
DISPLAY 0.617021 (-1885 2210);
PAINT ORANGE (-1885 2210);
FORCEPROP 2 LASTPIN (-1875 2150) $PN AT73
J 2
(-1885 2160);
DISPLAY 0.617021 (-1885 2160);
PAINT ORANGE (-1885 2160);
FORCEPROP 2 LASTPIN (-1875 2100) $PN AT77
J 2
(-1885 2110);
DISPLAY 0.617021 (-1885 2110);
PAINT ORANGE (-1885 2110);
FORCEPROP 2 LASTPIN (-1875 2050) $PN AT83
J 2
(-1885 2060);
DISPLAY 0.617021 (-1885 2060);
PAINT ORANGE (-1885 2060);
FORCEPROP 2 LASTPIN (-1875 2000) $PN AT85
J 2
(-1885 2010);
DISPLAY 0.617021 (-1885 2010);
PAINT ORANGE (-1885 2010);
FORCEPROP 2 LASTPIN (-1875 1950) $PN AU2
J 2
(-1885 1960);
DISPLAY 0.617021 (-1885 1960);
PAINT ORANGE (-1885 1960);
FORCEPROP 2 LASTPIN (-1875 1900) $PN AU6
J 2
(-1885 1910);
DISPLAY 0.617021 (-1885 1910);
PAINT ORANGE (-1885 1910);
FORCEPROP 2 LASTPIN (-1875 1850) $PN AU26
J 2
(-1885 1860);
DISPLAY 0.617021 (-1885 1860);
PAINT ORANGE (-1885 1860);
FORCEPROP 2 LASTPIN (-1875 1800) $PN AU28
J 2
(-1885 1810);
DISPLAY 0.617021 (-1885 1810);
PAINT ORANGE (-1885 1810);
FORCEPROP 2 LASTPIN (-1875 1750) $PN AU62
J 2
(-1885 1760);
DISPLAY 0.617021 (-1885 1760);
PAINT ORANGE (-1885 1760);
FORCEPROP 2 LASTPIN (-1875 1700) $PN AU64
J 2
(-1885 1710);
DISPLAY 0.617021 (-1885 1710);
PAINT ORANGE (-1885 1710);
FORCEPROP 2 LASTPIN (-1875 1650) $PN AU68
J 2
(-1885 1660);
DISPLAY 0.617021 (-1885 1660);
PAINT ORANGE (-1885 1660);
FORCEPROP 2 LASTPIN (-1875 1600) $PN AU74
J 2
(-1885 1610);
DISPLAY 0.617021 (-1885 1610);
PAINT ORANGE (-1885 1610);
FORCEPROP 2 LASTPIN (-1875 1550) $PN AU76
J 2
(-1885 1560);
DISPLAY 0.617021 (-1885 1560);
PAINT ORANGE (-1885 1560);
FORCEPROP 2 LASTPIN (-1875 1500) $PN AU78
J 2
(-1885 1510);
DISPLAY 0.617021 (-1885 1510);
PAINT ORANGE (-1885 1510);
FORCEPROP 2 LASTPIN (-1875 1450) $PN AU80
J 2
(-1885 1460);
DISPLAY 0.617021 (-1885 1460);
PAINT ORANGE (-1885 1460);
FORCEPROP 2 LASTPIN (-1875 1400) $PN AU84
J 2
(-1885 1410);
DISPLAY 0.617021 (-1885 1410);
PAINT ORANGE (-1885 1410);
FORCEPROP 2 LASTPIN (-1875 1350) $PN AU86
J 2
(-1885 1360);
DISPLAY 0.617021 (-1885 1360);
PAINT ORANGE (-1885 1360);
FORCEPROP 2 LASTPIN (-1875 1300) $PN AV1
J 2
(-1885 1310);
DISPLAY 0.617021 (-1885 1310);
PAINT ORANGE (-1885 1310);
FORCEPROP 2 LASTPIN (-1875 1250) $PN AV3
J 2
(-1885 1260);
DISPLAY 0.617021 (-1885 1260);
PAINT ORANGE (-1885 1260);
FORCEPROP 2 LASTPIN (-1875 1200) $PN AV7
J 2
(-1885 1210);
DISPLAY 0.617021 (-1885 1210);
PAINT ORANGE (-1885 1210);
FORCEPROP 2 LASTPIN (-1875 1150) $PN AV11
J 2
(-1885 1160);
DISPLAY 0.617021 (-1885 1160);
PAINT ORANGE (-1885 1160);
FORCEPROP 2 LASTPIN (-1875 1100) $PN AV13
J 2
(-1885 1110);
DISPLAY 0.617021 (-1885 1110);
PAINT ORANGE (-1885 1110);
FORCEPROP 2 LASTPIN (-1875 1050) $PN AV19
J 2
(-1885 1060);
DISPLAY 0.617021 (-1885 1060);
PAINT ORANGE (-1885 1060);
FORCEPROP 2 LASTPIN (-1875 1000) $PN AV23
J 2
(-1885 1010);
DISPLAY 0.617021 (-1885 1010);
PAINT ORANGE (-1885 1010);
FORCEPROP 2 LASTPIN (-1875 950) $PN AV25
J 2
(-1885 960);
DISPLAY 0.617021 (-1885 960);
PAINT ORANGE (-1885 960);
FORCEPROP 2 LASTPIN (-1875 900) $PN AV63
J 2
(-1885 910);
DISPLAY 0.617021 (-1885 910);
PAINT ORANGE (-1885 910);
FORCEPROP 2 LASTPIN (-1875 850) $PN AV65
J 2
(-1885 860);
DISPLAY 0.617021 (-1885 860);
PAINT ORANGE (-1885 860);
FORCEPROP 2 LASTPIN (-1875 800) $PN AV67
J 2
(-1885 810);
DISPLAY 0.617021 (-1885 810);
PAINT ORANGE (-1885 810);
FORCEPROP 2 LASTPIN (-1875 750) $PN AV75
J 2
(-1885 760);
DISPLAY 0.617021 (-1885 760);
PAINT ORANGE (-1885 760);
FORCEPROP 2 LASTPIN (-1875 700) $PN AV83
J 2
(-1885 710);
DISPLAY 0.617021 (-1885 710);
PAINT ORANGE (-1885 710);
FORCEPROP 2 LASTPIN (-1875 650) $PN AW2
J 2
(-1885 660);
DISPLAY 0.617021 (-1885 660);
PAINT ORANGE (-1885 660);
FORCEPROP 2 LASTPIN (-675 4600) $PN AW10
J 0
(-665 4610);
DISPLAY 0.617021 (-665 4610);
PAINT ORANGE (-665 4610);
FORCEPROP 2 LASTPIN (-675 4550) $PN AW62
J 0
(-665 4560);
DISPLAY 0.617021 (-665 4560);
PAINT ORANGE (-665 4560);
FORCEPROP 2 LASTPIN (-675 4500) $PN AW66
J 0
(-665 4510);
DISPLAY 0.617021 (-665 4510);
PAINT ORANGE (-665 4510);
FORCEPROP 2 LASTPIN (-675 4450) $PN AW68
J 0
(-665 4460);
DISPLAY 0.617021 (-665 4460);
PAINT ORANGE (-665 4460);
FORCEPROP 2 LASTPIN (-675 4400) $PN AW70
J 0
(-665 4410);
DISPLAY 0.617021 (-665 4410);
PAINT ORANGE (-665 4410);
FORCEPROP 2 LASTPIN (-675 4350) $PN AW72
J 0
(-665 4360);
DISPLAY 0.617021 (-665 4360);
PAINT ORANGE (-665 4360);
FORCEPROP 2 LASTPIN (-675 4300) $PN AW74
J 0
(-665 4310);
DISPLAY 0.617021 (-665 4310);
PAINT ORANGE (-665 4310);
FORCEPROP 2 LASTPIN (-675 4250) $PN AW78
J 0
(-665 4260);
DISPLAY 0.617021 (-665 4260);
PAINT ORANGE (-665 4260);
FORCEPROP 2 LASTPIN (-675 4200) $PN AW82
J 0
(-665 4210);
DISPLAY 0.617021 (-665 4210);
PAINT ORANGE (-665 4210);
FORCEPROP 2 LASTPIN (-675 4150) $PN AW84
J 0
(-665 4160);
DISPLAY 0.617021 (-665 4160);
PAINT ORANGE (-665 4160);
FORCEPROP 2 LASTPIN (-675 4100) $PN AY5
J 0
(-665 4110);
DISPLAY 0.617021 (-665 4110);
PAINT ORANGE (-665 4110);
FORCEPROP 2 LASTPIN (-675 4050) $PN AY15
J 0
(-665 4060);
DISPLAY 0.617021 (-665 4060);
PAINT ORANGE (-665 4060);
FORCEPROP 2 LASTPIN (-675 4000) $PN AY17
J 0
(-665 4010);
DISPLAY 0.617021 (-665 4010);
PAINT ORANGE (-665 4010);
FORCEPROP 2 LASTPIN (-675 3950) $PN AY21
J 0
(-665 3960);
DISPLAY 0.617021 (-665 3960);
PAINT ORANGE (-665 3960);
FORCEPROP 2 LASTPIN (-675 3900) $PN AY23
J 0
(-665 3910);
DISPLAY 0.617021 (-665 3910);
PAINT ORANGE (-665 3910);
FORCEPROP 2 LASTPIN (-675 3850) $PN AY25
J 0
(-665 3860);
DISPLAY 0.617021 (-665 3860);
PAINT ORANGE (-665 3860);
FORCEPROP 2 LASTPIN (-675 3800) $PN AY63
J 0
(-665 3810);
DISPLAY 0.617021 (-665 3810);
PAINT ORANGE (-665 3810);
FORCEPROP 2 LASTPIN (-675 3750) $PN AY79
J 0
(-665 3760);
DISPLAY 0.617021 (-665 3760);
PAINT ORANGE (-665 3760);
FORCEPROP 2 LASTPIN (-675 3700) $PN AY81
J 0
(-665 3710);
DISPLAY 0.617021 (-665 3710);
PAINT ORANGE (-665 3710);
FORCEPROP 2 LASTPIN (-675 3650) $PN BA2
J 0
(-665 3660);
DISPLAY 0.617021 (-665 3660);
PAINT ORANGE (-665 3660);
FORCEPROP 2 LASTPIN (-675 3600) $PN BA6
J 0
(-665 3610);
DISPLAY 0.617021 (-665 3610);
PAINT ORANGE (-665 3610);
FORCEPROP 2 LASTPIN (-675 3550) $PN BA12
J 0
(-665 3560);
DISPLAY 0.617021 (-665 3560);
PAINT ORANGE (-665 3560);
FORCEPROP 2 LASTPIN (-675 3500) $PN BA62
J 0
(-665 3510);
DISPLAY 0.617021 (-665 3510);
PAINT ORANGE (-665 3510);
FORCEPROP 2 LASTPIN (-675 3450) $PN BA68
J 0
(-665 3460);
DISPLAY 0.617021 (-665 3460);
PAINT ORANGE (-665 3460);
FORCEPROP 2 LASTPIN (-675 3400) $PN BA74
J 0
(-665 3410);
DISPLAY 0.617021 (-665 3410);
PAINT ORANGE (-665 3410);
FORCEPROP 2 LASTPIN (-675 3350) $PN BA80
J 0
(-665 3360);
DISPLAY 0.617021 (-665 3360);
PAINT ORANGE (-665 3360);
FORCEPROP 2 LASTPIN (-675 3300) $PN BA84
J 0
(-665 3310);
DISPLAY 0.617021 (-665 3310);
PAINT ORANGE (-665 3310);
FORCEPROP 2 LASTPIN (-675 3250) $PN BB19
J 0
(-665 3260);
DISPLAY 0.617021 (-665 3260);
PAINT ORANGE (-665 3260);
FORCEPROP 2 LASTPIN (-675 3200) $PN BB23
J 0
(-665 3210);
DISPLAY 0.617021 (-665 3210);
PAINT ORANGE (-665 3210);
FORCEPROP 2 LASTPIN (-675 3150) $PN BB63
J 0
(-665 3160);
DISPLAY 0.617021 (-665 3160);
PAINT ORANGE (-665 3160);
FORCEPROP 2 LASTPIN (-675 3100) $PN BB69
J 0
(-665 3110);
DISPLAY 0.617021 (-665 3110);
PAINT ORANGE (-665 3110);
FORCEPROP 2 LASTPIN (-675 3050) $PN BB73
J 0
(-665 3060);
DISPLAY 0.617021 (-665 3060);
PAINT ORANGE (-665 3060);
FORCEPROP 2 LASTPIN (-675 3000) $PN BB75
J 0
(-665 3010);
DISPLAY 0.617021 (-665 3010);
PAINT ORANGE (-665 3010);
FORCEPROP 2 LASTPIN (-675 2950) $PN BB77
J 0
(-665 2960);
DISPLAY 0.617021 (-665 2960);
PAINT ORANGE (-665 2960);
FORCEPROP 2 LASTPIN (-675 2900) $PN BB79
J 0
(-665 2910);
DISPLAY 0.617021 (-665 2910);
PAINT ORANGE (-665 2910);
FORCEPROP 2 LASTPIN (-675 2850) $PN BB81
J 0
(-665 2860);
DISPLAY 0.617021 (-665 2860);
PAINT ORANGE (-665 2860);
FORCEPROP 2 LASTPIN (-675 2800) $PN BB83
J 0
(-665 2810);
DISPLAY 0.617021 (-665 2810);
PAINT ORANGE (-665 2810);
FORCEPROP 2 LASTPIN (-675 2750) $PN BC4
J 0
(-665 2760);
DISPLAY 0.617021 (-665 2760);
PAINT ORANGE (-665 2760);
FORCEPROP 2 LASTPIN (-675 2700) $PN BC8
J 0
(-665 2710);
DISPLAY 0.617021 (-665 2710);
PAINT ORANGE (-665 2710);
FORCEPROP 2 LASTPIN (-675 2650) $PN BC12
J 0
(-665 2660);
DISPLAY 0.617021 (-665 2660);
PAINT ORANGE (-665 2660);
FORCEPROP 2 LASTPIN (-675 2600) $PN BC16
J 0
(-665 2610);
DISPLAY 0.617021 (-665 2610);
PAINT ORANGE (-665 2610);
FORCEPROP 2 LASTPIN (-675 2550) $PN BC70
J 0
(-665 2560);
DISPLAY 0.617021 (-665 2560);
PAINT ORANGE (-665 2560);
FORCEPROP 2 LASTPIN (-675 2500) $PN BC72
J 0
(-665 2510);
DISPLAY 0.617021 (-665 2510);
PAINT ORANGE (-665 2510);
FORCEPROP 2 LASTPIN (-675 2450) $PN BC74
J 0
(-665 2460);
DISPLAY 0.617021 (-665 2460);
PAINT ORANGE (-665 2460);
FORCEPROP 2 LASTPIN (-675 2400) $PN BC76
J 0
(-665 2410);
DISPLAY 0.617021 (-665 2410);
PAINT ORANGE (-665 2410);
FORCEPROP 2 LASTPIN (-675 2350) $PN BC78
J 0
(-665 2360);
DISPLAY 0.617021 (-665 2360);
PAINT ORANGE (-665 2360);
FORCEPROP 2 LASTPIN (-675 2300) $PN BC80
J 0
(-665 2310);
DISPLAY 0.617021 (-665 2310);
PAINT ORANGE (-665 2310);
FORCEPROP 2 LASTPIN (-675 2250) $PN BC82
J 0
(-665 2260);
DISPLAY 0.617021 (-665 2260);
PAINT ORANGE (-665 2260);
FORCEPROP 2 LASTPIN (-675 2200) $PN BD5
J 0
(-665 2210);
DISPLAY 0.617021 (-665 2210);
PAINT ORANGE (-665 2210);
FORCEPROP 2 LASTPIN (-675 2150) $PN BD11
J 0
(-665 2160);
DISPLAY 0.617021 (-665 2160);
PAINT ORANGE (-665 2160);
FORCEPROP 2 LASTPIN (-675 2100) $PN BD15
J 0
(-665 2110);
DISPLAY 0.617021 (-665 2110);
PAINT ORANGE (-665 2110);
FORCEPROP 2 LASTPIN (-675 2050) $PN BD21
J 0
(-665 2060);
DISPLAY 0.617021 (-665 2060);
PAINT ORANGE (-665 2060);
FORCEPROP 2 LASTPIN (-675 2000) $PN BD27
J 0
(-665 2010);
DISPLAY 0.617021 (-665 2010);
PAINT ORANGE (-665 2010);
FORCEPROP 2 LASTPIN (-675 1950) $PN BD63
J 0
(-665 1960);
DISPLAY 0.617021 (-665 1960);
PAINT ORANGE (-665 1960);
FORCEPROP 2 LASTPIN (-675 1900) $PN BD71
J 0
(-665 1910);
DISPLAY 0.617021 (-665 1910);
PAINT ORANGE (-665 1910);
FORCEPROP 2 LASTPIN (-675 1850) $PN BE4
J 0
(-665 1860);
DISPLAY 0.617021 (-665 1860);
PAINT ORANGE (-665 1860);
FORCEPROP 2 LASTPIN (-675 1800) $PN BE6
J 0
(-665 1810);
DISPLAY 0.617021 (-665 1810);
PAINT ORANGE (-665 1810);
FORCEPROP 2 LASTPIN (-675 1750) $PN BE8
J 0
(-665 1760);
DISPLAY 0.617021 (-665 1760);
PAINT ORANGE (-665 1760);
FORCEPROP 2 LASTPIN (-675 1700) $PN BE10
J 0
(-665 1710);
DISPLAY 0.617021 (-665 1710);
PAINT ORANGE (-665 1710);
FORCEPROP 2 LASTPIN (-675 1650) $PN BE26
J 0
(-665 1660);
DISPLAY 0.617021 (-665 1660);
PAINT ORANGE (-665 1660);
FORCEPROP 2 LASTPIN (-675 1600) $PN BE64
J 0
(-665 1610);
DISPLAY 0.617021 (-665 1610);
PAINT ORANGE (-665 1610);
FORCEPROP 2 LASTPIN (-675 1550) $PN BE66
J 0
(-665 1560);
DISPLAY 0.617021 (-665 1560);
PAINT ORANGE (-665 1560);
FORCEPROP 2 LASTPIN (-675 1500) $PN BE68
J 0
(-665 1510);
DISPLAY 0.617021 (-665 1510);
PAINT ORANGE (-665 1510);
FORCEPROP 2 LASTPIN (-675 1450) $PN BE70
J 0
(-665 1460);
DISPLAY 0.617021 (-665 1460);
PAINT ORANGE (-665 1460);
FORCEPROP 2 LASTPIN (-675 1400) $PN BF9
J 0
(-665 1410);
DISPLAY 0.617021 (-665 1410);
PAINT ORANGE (-665 1410);
FORCEPROP 2 LASTPIN (-675 1350) $PN BF15
J 0
(-665 1360);
DISPLAY 0.617021 (-665 1360);
PAINT ORANGE (-665 1360);
FORCEPROP 2 LASTPIN (-675 1300) $PN BF17
J 0
(-665 1310);
DISPLAY 0.617021 (-665 1310);
PAINT ORANGE (-665 1310);
FORCEPROP 2 LASTPIN (-675 1250) $PN BF19
J 0
(-665 1260);
DISPLAY 0.617021 (-665 1260);
PAINT ORANGE (-665 1260);
FORCEPROP 2 LASTPIN (-675 1200) $PN BF25
J 0
(-665 1210);
DISPLAY 0.617021 (-665 1210);
PAINT ORANGE (-665 1210);
FORCEPROP 2 LASTPIN (-675 1150) $PN BF63
J 0
(-665 1160);
DISPLAY 0.617021 (-665 1160);
PAINT ORANGE (-665 1160);
FORCEPROP 2 LASTPIN (-675 1100) $PN BF65
J 0
(-665 1110);
DISPLAY 0.617021 (-665 1110);
PAINT ORANGE (-665 1110);
FORCEPROP 2 LASTPIN (-675 1050) $PN BF67
J 0
(-665 1060);
DISPLAY 0.617021 (-665 1060);
PAINT ORANGE (-665 1060);
FORCEPROP 2 LASTPIN (-675 1000) $PN BF69
J 0
(-665 1010);
DISPLAY 0.617021 (-665 1010);
PAINT ORANGE (-665 1010);
FORCEPROP 2 LASTPIN (-675 950) $PN BF71
J 0
(-665 960);
DISPLAY 0.617021 (-665 960);
PAINT ORANGE (-665 960);
FORCEPROP 2 LASTPIN (-675 900) $PN BG6
J 0
(-665 910);
DISPLAY 0.617021 (-665 910);
PAINT ORANGE (-665 910);
FORCEPROP 2 LASTPIN (-675 850) $PN BG8
J 0
(-665 860);
DISPLAY 0.617021 (-665 860);
PAINT ORANGE (-665 860);
FORCEPROP 2 LASTPIN (-675 800) $PN BG10
J 0
(-665 810);
DISPLAY 0.617021 (-665 810);
PAINT ORANGE (-665 810);
FORCEPROP 2 LASTPIN (-675 750) $PN BG22
J 0
(-665 760);
DISPLAY 0.617021 (-665 760);
PAINT ORANGE (-665 760);
FORCEPROP 2 LASTPIN (-675 700) $PN BG24
J 0
(-665 710);
DISPLAY 0.617021 (-665 710);
PAINT ORANGE (-665 710);
FORCEPROP 2 LASTPIN (-675 650) $PN BG72
J 0
(-665 660);
DISPLAY 0.617021 (-665 660);
PAINT ORANGE (-665 660);
FORCEPROP 1 LAST PACK_TYPE BGA1
J 0
(-1825 4900);
PAINT SKYBLUE (-1825 4900);
DISPLAY INVISIBLE (-1825 4900);
FORCEPROP 2 LAST SEC_TYPE BGA1
J 0
(-1825 4900);
DISPLAY 1.021277 (-1825 4900);
PAINT ORANGE (-1825 4900);
DISPLAY INVISIBLE (-1825 4900);
FORCEPROP 2 LAST CDS_LIB chpset_lib
J 0
(-1275 2600);
PAINT ORANGE (-1275 2600);
DISPLAY INVISIBLE (-1275 2600);
FORCEPROP 2 LAST SEC 26
J 0
(-1825 4900);
DISPLAY 0.680851 (-1825 4900);
PAINT MONO (-1825 4900);
DISPLAY INVISIBLE (-1825 4900);
FORCEPROP 2 LAST CDS_LOCATION U2D1
J 0
(-1825 4850);
DISPLAY 0.617021 (-1825 4850);
PAINT AQUA (-1825 4850);
DISPLAY INVISIBLE (-1825 4850);
FORCEPROP 1 LAST PATH I23
J 0
(-1275 4800);
PAINT GREEN (-1275 4800);
DISPLAY INVISIBLE (-1275 4800);
FORCEADD GND..1
(-6100 475);
FORCEPROP 3 LASTPIN (-6100 525) SIG_NAME GND\g
J 0
(-6090 535);
DISPLAY 0.659574 (-6090 535);
PAINT MONO (-6090 535);
DISPLAY INVISIBLE (-6090 535);
FORCEPROP 1 LAST VOLTAGE 0.0V
J 0
(-6145 432);
DISPLAY 0.340426 (-6145 432);
PAINT SKYBLUE (-6145 432);
DISPLAY INVISIBLE (-6145 432);
FORCEPROP 1 LAST SIZE 1B
J 0
(-6025 425);
DISPLAY 1.170213 (-6025 425);
PAINT AQUA (-6025 425);
DISPLAY INVISIBLE (-6025 425);
FORCEPROP 2 LAST CDS_LIB mstr_symbols
J 0
(-6100 475);
PAINT ORANGE (-6100 475);
DISPLAY INVISIBLE (-6100 475);
FORCEPROP 1 LAST BODY_TYPE PLUMBING
J 0
(-6145 432);
DISPLAY 0.340426 (-6145 432);
PAINT GREEN (-6145 432);
DISPLAY INVISIBLE (-6145 432);
FORCEPROP 1 LAST PATH I3
J 0
(-6025 475);
DISPLAY 1.170213 (-6025 475);
PAINT AQUA (-6025 475);
DISPLAY INVISIBLE (-6025 475);
FORCEPROP 1 LAST HDL_POWER GND
J 0
(-6100 625);
DISPLAY 1.170213 (-6100 625);
PAINT GREEN (-6100 625);
DISPLAY INVISIBLE (-6100 625);
FORCEADD GND..1
(-5775 500);
FORCEPROP 3 LASTPIN (-5775 550) SIG_NAME GND\g
J 0
(-5765 560);
DISPLAY 0.659574 (-5765 560);
PAINT MONO (-5765 560);
DISPLAY INVISIBLE (-5765 560);
FORCEPROP 1 LAST VOLTAGE 0.0V
J 0
(-5820 457);
DISPLAY 0.340426 (-5820 457);
PAINT SKYBLUE (-5820 457);
DISPLAY INVISIBLE (-5820 457);
FORCEPROP 1 LAST SIZE 1B
J 0
(-5700 450);
DISPLAY 1.170213 (-5700 450);
PAINT AQUA (-5700 450);
DISPLAY INVISIBLE (-5700 450);
FORCEPROP 2 LAST CDS_LIB mstr_symbols
J 0
(-5775 500);
PAINT ORANGE (-5775 500);
DISPLAY INVISIBLE (-5775 500);
FORCEPROP 1 LAST BODY_TYPE PLUMBING
J 0
(-5820 457);
DISPLAY 0.340426 (-5820 457);
PAINT GREEN (-5820 457);
DISPLAY INVISIBLE (-5820 457);
FORCEPROP 1 LAST PATH I4
J 0
(-5700 500);
DISPLAY 1.170213 (-5700 500);
PAINT AQUA (-5700 500);
DISPLAY INVISIBLE (-5700 500);
FORCEPROP 1 LAST HDL_POWER GND
J 0
(-5775 650);
DISPLAY 1.170213 (-5775 650);
PAINT GREEN (-5775 650);
DISPLAY INVISIBLE (-5775 650);
FORCEADD GND..1
(-4250 500);
FORCEPROP 3 LASTPIN (-4250 550) SIG_NAME GND\g
J 0
(-4240 560);
DISPLAY 0.659574 (-4240 560);
PAINT MONO (-4240 560);
DISPLAY INVISIBLE (-4240 560);
FORCEPROP 1 LAST VOLTAGE 0.0V
J 0
(-4295 457);
DISPLAY 0.340426 (-4295 457);
PAINT SKYBLUE (-4295 457);
DISPLAY INVISIBLE (-4295 457);
FORCEPROP 1 LAST SIZE 1B
J 0
(-4175 450);
DISPLAY 1.170213 (-4175 450);
PAINT AQUA (-4175 450);
DISPLAY INVISIBLE (-4175 450);
FORCEPROP 2 LAST CDS_LIB mstr_symbols
J 0
(-4250 500);
PAINT ORANGE (-4250 500);
DISPLAY INVISIBLE (-4250 500);
FORCEPROP 1 LAST BODY_TYPE PLUMBING
J 0
(-4295 457);
DISPLAY 0.340426 (-4295 457);
PAINT GREEN (-4295 457);
DISPLAY INVISIBLE (-4295 457);
FORCEPROP 1 LAST PATH I6
J 0
(-4175 500);
DISPLAY 1.170213 (-4175 500);
PAINT AQUA (-4175 500);
DISPLAY INVISIBLE (-4175 500);
FORCEPROP 1 LAST HDL_POWER GND
J 0
(-4250 650);
DISPLAY 1.170213 (-4250 650);
PAINT GREEN (-4250 650);
DISPLAY INVISIBLE (-4250 650);
FORCEADD GND..1
(-3950 500);
FORCEPROP 3 LASTPIN (-3950 550) SIG_NAME GND\g
J 0
(-3940 560);
DISPLAY 0.659574 (-3940 560);
PAINT MONO (-3940 560);
DISPLAY INVISIBLE (-3940 560);
FORCEPROP 1 LAST VOLTAGE 0.0V
J 0
(-3995 457);
DISPLAY 0.340426 (-3995 457);
PAINT SKYBLUE (-3995 457);
DISPLAY INVISIBLE (-3995 457);
FORCEPROP 2 LAST CDS_LIB mstr_symbols
J 0
(-3950 500);
PAINT ORANGE (-3950 500);
DISPLAY INVISIBLE (-3950 500);
FORCEPROP 1 LAST SIZE 1B
J 0
(-3875 450);
DISPLAY 1.170213 (-3875 450);
PAINT AQUA (-3875 450);
DISPLAY INVISIBLE (-3875 450);
FORCEPROP 1 LAST BODY_TYPE PLUMBING
J 0
(-3995 457);
DISPLAY 0.340426 (-3995 457);
PAINT GREEN (-3995 457);
DISPLAY INVISIBLE (-3995 457);
FORCEPROP 1 LAST PATH I9
J 0
(-3875 500);
DISPLAY 0.872340 (-3875 500);
PAINT AQUA (-3875 500);
DISPLAY INVISIBLE (-3875 500);
FORCEPROP 1 LAST HDL_POWER GND
J 0
(-3950 650);
DISPLAY 1.170213 (-3950 650);
PAINT GREEN (-3950 650);
DISPLAY INVISIBLE (-3950 650);
FORCEADD DESIGN_NOTE..1
(-6500 275);
FORCEPROP 0 LAST L1 CPU SYMBOLS 1-30 ARE PRELIMINARY AND SUBJECT TO CHANGE
J 0
(-6700 150);
DISPLAY 1.021277 (-6700 150);
PAINT ORANGE (-6700 150);
FORCEPROP 2 LAST CDS_LIB mstr_symbols
J 0
(-6500 275);
PAINT ORANGE (-6500 275);
DISPLAY INVISIBLE (-6500 275);
FORCEPROP 1 LAST COMMENT_BODY TRUE
J 0
(-6475 375);
DISPLAY 0.978723 (-6475 375);
PAINT ORANGE (-6475 375);
DISPLAY INVISIBLE (-6475 375);
FORCEADD PRELIM..10
(-1265 2590);
PAINT GRAY (-1265 2590);
FORCEPROP 2 LAST CDS_LIB mstr_misc
J 0
(-1265 2590);
PAINT ORANGE (-1265 2590);
DISPLAY INVISIBLE (-1265 2590);
FORCEPROP 1 LAST COMMENT_BODY TRUE
J 0
(-1265 2590);
PAINT ORANGE (-1265 2590);
DISPLAY INVISIBLE (-1265 2590);
FORCEADD PRELIM..10
(-5015 2615);
PAINT GRAY (-5015 2615);
FORCEPROP 2 LAST CDS_LIB mstr_misc
J 0
(-5015 2615);
PAINT ORANGE (-5015 2615);
DISPLAY INVISIBLE (-5015 2615);
FORCEPROP 1 LAST COMMENT_BODY TRUE
J 0
(-5015 2615);
PAINT ORANGE (-5015 2615);
DISPLAY INVISIBLE (-5015 2615);
FORCEADD PRELIM..10
(-6865 2615);
PAINT GRAY (-6865 2615);
FORCEPROP 2 LAST CDS_LIB mstr_misc
J 0
(-6865 2615);
PAINT ORANGE (-6865 2615);
DISPLAY INVISIBLE (-6865 2615);
FORCEPROP 1 LAST COMMENT_BODY TRUE
J 0
(-6865 2615);
PAINT ORANGE (-6865 2615);
DISPLAY INVISIBLE (-6865 2615);
FORCEADD PRELIM..10
(-3190 2615);
PAINT GRAY (-3190 2615);
FORCEPROP 2 LAST CDS_LIB mstr_misc
J 0
(-3190 2615);
PAINT ORANGE (-3190 2615);
DISPLAY INVISIBLE (-3190 2615);
FORCEPROP 1 LAST COMMENT_BODY TRUE
J 0
(-3190 2615);
PAINT ORANGE (-3190 2615);
DISPLAY INVISIBLE (-3190 2615);
FORCEADD INTEL_CORP_BPAGE..1
(-100 50);
FORCEPROP 1 LAST CDS_CON_LAST_MODIFIED Tue Dec 01 11:51:39 2015
J 0
(-1525 375);
DISPLAY 1.340426 (-1525 375);
PAINT GREEN (-1525 375);
DISPLAY INVISIBLE (-1525 375);
FORCEPROP 1 LAST CUSTOM_TXT_CDS <CURRENT_DESIGN_SHEET> OF <TOTAL_DESIGN_SHEETS>
J 0
(-600 75);
PAINT GREEN (-600 75);
FORCEPROP 1 LAST CUSTOM_TXT_CDS <CON_LAST_MODIFIED>
J 0
(-2025 400);
PAINT GREEN (-2025 400);
FORCEPROP 2 LAST CUSTOM_TXT_CDS <XR_PAGE_TITLE>
J 0
(-7990 5300);
DISPLAY 0.638298 (-7990 5300);
PAINT PINK (-7990 5300);
DISPLAY INVISIBLE (-7990 5300);
FORCEPROP 1 LAST SCH_ADDRESS3 Santa Clara, CA 95052-8119
J 0
(-4075 75);
DISPLAY 0.617021 (-4075 75);
PAINT GREEN (-4075 75);
FORCEPROP 1 LAST SCH_ADDRESS2 P.O. BOX 58119
J 0
(-4075 125);
DISPLAY 0.617021 (-4075 125);
PAINT GREEN (-4075 125);
FORCEPROP 1 LAST SCH_ADDRESS1 2200 Mission College Blvd.
J 0
(-4075 175);
DISPLAY 0.617021 (-4075 175);
PAINT GREEN (-4075 175);
FORCEPROP 1 LAST SCH_TITLE SKYLAKE - SKT1 - 20 OF 21
J 0
(-8050 100);
DISPLAY 1.212766 (-8050 100);
PAINT GREEN (-8050 100);
FORCEPROP 1 LAST SCH_NUMBER H4694802
J 0
(-1400 200);
DISPLAY 1.212766 (-1400 200);
PAINT YELLOW (-1400 200);
FORCEPROP 1 LAST SCH_DEPT BESD
J 1
(-4550 150);
DISPLAY 1.212766 (-4550 150);
PAINT YELLOW (-4550 150);
FORCEPROP 1 LAST SCH_REV 2.420
J 0
(-350 200);
DISPLAY 0.978723 (-350 200);
PAINT YELLOW (-350 200);
FORCEPROP 2 LAST CDS_LIB mstr_symbols
J 0
(-100 50);
PAINT ORANGE (-100 50);
DISPLAY INVISIBLE (-100 50);
FORCEPROP 2 LAST PAGE_BORDER TRUE
J 0
(-7990 5300);
DISPLAY 0.851064 (-7990 5300);
PAINT PINK (-7990 5300);
DISPLAY INVISIBLE (-7990 5300);
FORCEPROP 1 LAST COMMENT_BODY TRUE
J 0
(-88 62);
DISPLAY 0.638298 (-88 62);
PAINT GREEN (-88 62);
DISPLAY INVISIBLE (-88 62);
FORCEPROP 2 LAST CDS_XR_PAGE_TITLE CR-74 : @BASEBOARD_FAB2_LIB.BASEBOARD_FAB2(SCH_1):PAGE74
J 0
(-7990 5300);
DISPLAY 0.638298 (-7990 5300);
PAINT PINK (-7990 5300);
DISPLAY INVISIBLE (-7990 5300);
WIRE 16 -1 (-7625 4600)(-7475 4600);
WIRE 16 -1 (-7625 4600)(-7625 4550);
WIRE 16 -1 (-7475 4550)(-7625 4550);
WIRE 16 -1 (-7625 4550)(-7625 4500);
WIRE 16 -1 (-7475 4500)(-7625 4500);
WIRE 16 -1 (-7625 4500)(-7625 4450);
WIRE 16 -1 (-7475 4450)(-7625 4450);
WIRE 16 -1 (-7625 4450)(-7625 4400);
WIRE 16 -1 (-7475 4400)(-7625 4400);
WIRE 16 -1 (-7625 4400)(-7625 4350);
WIRE 16 -1 (-7475 4350)(-7625 4350);
WIRE 16 -1 (-7625 4350)(-7625 4300);
WIRE 16 -1 (-7475 4300)(-7625 4300);
WIRE 16 -1 (-7625 4300)(-7625 4250);
WIRE 16 -1 (-7475 4250)(-7625 4250);
WIRE 16 -1 (-7625 4250)(-7625 4200);
WIRE 16 -1 (-7475 4200)(-7625 4200);
WIRE 16 -1 (-7625 4200)(-7625 4150);
WIRE 16 -1 (-7475 4150)(-7625 4150);
WIRE 16 -1 (-7625 4150)(-7625 4100);
WIRE 16 -1 (-7475 4100)(-7625 4100);
WIRE 16 -1 (-7625 4100)(-7625 4050);
WIRE 16 -1 (-7475 4050)(-7625 4050);
WIRE 16 -1 (-7625 4050)(-7625 4000);
WIRE 16 -1 (-7475 4000)(-7625 4000);
WIRE 16 -1 (-7625 4000)(-7625 3950);
WIRE 16 -1 (-7475 3950)(-7625 3950);
WIRE 16 -1 (-7625 3950)(-7625 3900);
WIRE 16 -1 (-7475 3900)(-7625 3900);
WIRE 16 -1 (-7625 3900)(-7625 3850);
WIRE 16 -1 (-7475 3850)(-7625 3850);
WIRE 16 -1 (-7625 3850)(-7625 3800);
WIRE 16 -1 (-7475 3800)(-7625 3800);
WIRE 16 -1 (-7625 3800)(-7625 3750);
WIRE 16 -1 (-7475 3750)(-7625 3750);
WIRE 16 -1 (-7625 3750)(-7625 3700);
WIRE 16 -1 (-7475 3700)(-7625 3700);
WIRE 16 -1 (-7625 3700)(-7625 3650);
WIRE 16 -1 (-7475 3650)(-7625 3650);
WIRE 16 -1 (-7625 3650)(-7625 3600);
WIRE 16 -1 (-7475 3600)(-7625 3600);
WIRE 16 -1 (-7625 3600)(-7625 3550);
WIRE 16 -1 (-7475 3550)(-7625 3550);
WIRE 16 -1 (-7625 3550)(-7625 3500);
WIRE 16 -1 (-7475 3500)(-7625 3500);
WIRE 16 -1 (-7625 3500)(-7625 3450);
WIRE 16 -1 (-7475 3450)(-7625 3450);
WIRE 16 -1 (-7625 3450)(-7625 3400);
WIRE 16 -1 (-7475 3400)(-7625 3400);
WIRE 16 -1 (-7625 3400)(-7625 3350);
WIRE 16 -1 (-7475 3350)(-7625 3350);
WIRE 16 -1 (-7625 3350)(-7625 3300);
WIRE 16 -1 (-7475 3300)(-7625 3300);
WIRE 16 -1 (-7625 3300)(-7625 3250);
WIRE 16 -1 (-7475 3250)(-7625 3250);
WIRE 16 -1 (-7625 3250)(-7625 3200);
WIRE 16 -1 (-7475 3200)(-7625 3200);
WIRE 16 -1 (-7625 3200)(-7625 3150);
WIRE 16 -1 (-7475 3150)(-7625 3150);
WIRE 16 -1 (-7625 3150)(-7625 3100);
WIRE 16 -1 (-7475 3100)(-7625 3100);
WIRE 16 -1 (-7625 3100)(-7625 3050);
WIRE 16 -1 (-7475 3050)(-7625 3050);
WIRE 16 -1 (-7625 3050)(-7625 3000);
WIRE 16 -1 (-7475 3000)(-7625 3000);
WIRE 16 -1 (-7625 3000)(-7625 2950);
WIRE 16 -1 (-7475 2950)(-7625 2950);
WIRE 16 -1 (-7625 2950)(-7625 2900);
WIRE 16 -1 (-7475 2900)(-7625 2900);
WIRE 16 -1 (-7625 2900)(-7625 2850);
WIRE 16 -1 (-7475 2850)(-7625 2850);
WIRE 16 -1 (-7625 2850)(-7625 2800);
WIRE 16 -1 (-7475 2800)(-7625 2800);
WIRE 16 -1 (-7625 2800)(-7625 2750);
WIRE 16 -1 (-7475 2750)(-7625 2750);
WIRE 16 -1 (-7625 2750)(-7625 2700);
WIRE 16 -1 (-7475 2700)(-7625 2700);
WIRE 16 -1 (-7625 2700)(-7625 2650);
WIRE 16 -1 (-7475 2650)(-7625 2650);
WIRE 16 -1 (-7625 2650)(-7625 2600);
WIRE 16 -1 (-7475 2600)(-7625 2600);
WIRE 16 -1 (-7625 2600)(-7625 2550);
WIRE 16 -1 (-7475 2550)(-7625 2550);
WIRE 16 -1 (-7625 2550)(-7625 2500);
WIRE 16 -1 (-7475 2500)(-7625 2500);
WIRE 16 -1 (-7625 2500)(-7625 2450);
WIRE 16 -1 (-7475 2450)(-7625 2450);
WIRE 16 -1 (-7625 2450)(-7625 2400);
WIRE 16 -1 (-7475 2400)(-7625 2400);
WIRE 16 -1 (-7625 2400)(-7625 2350);
WIRE 16 -1 (-7475 2350)(-7625 2350);
WIRE 16 -1 (-7625 2350)(-7625 2300);
WIRE 16 -1 (-7475 2300)(-7625 2300);
WIRE 16 -1 (-7625 2300)(-7625 2250);
WIRE 16 -1 (-7475 2250)(-7625 2250);
WIRE 16 -1 (-7625 2250)(-7625 2200);
WIRE 16 -1 (-7475 2200)(-7625 2200);
WIRE 16 -1 (-7625 2200)(-7625 2150);
WIRE 16 -1 (-7475 2150)(-7625 2150);
WIRE 16 -1 (-7625 2150)(-7625 2100);
WIRE 16 -1 (-7475 2100)(-7625 2100);
WIRE 16 -1 (-7625 2100)(-7625 2050);
WIRE 16 -1 (-7475 2050)(-7625 2050);
WIRE 16 -1 (-7625 2050)(-7625 2000);
WIRE 16 -1 (-7475 2000)(-7625 2000);
WIRE 16 -1 (-7625 2000)(-7625 1950);
WIRE 16 -1 (-7475 1950)(-7625 1950);
WIRE 16 -1 (-7625 1950)(-7625 1900);
WIRE 16 -1 (-7475 1900)(-7625 1900);
WIRE 16 -1 (-7625 1900)(-7625 1850);
WIRE 16 -1 (-7475 1850)(-7625 1850);
WIRE 16 -1 (-7625 1850)(-7625 1800);
WIRE 16 -1 (-7475 1800)(-7625 1800);
WIRE 16 -1 (-7625 1800)(-7625 1750);
WIRE 16 -1 (-7475 1750)(-7625 1750);
WIRE 16 -1 (-7625 1750)(-7625 1700);
WIRE 16 -1 (-7475 1700)(-7625 1700);
WIRE 16 -1 (-7625 1700)(-7625 1650);
WIRE 16 -1 (-7475 1650)(-7625 1650);
WIRE 16 -1 (-7625 1650)(-7625 1600);
WIRE 16 -1 (-7475 1600)(-7625 1600);
WIRE 16 -1 (-7625 1600)(-7625 1550);
WIRE 16 -1 (-7475 1550)(-7625 1550);
WIRE 16 -1 (-7625 1550)(-7625 1500);
WIRE 16 -1 (-7475 1500)(-7625 1500);
WIRE 16 -1 (-7625 1500)(-7625 1450);
WIRE 16 -1 (-7475 1450)(-7625 1450);
WIRE 16 -1 (-7625 1450)(-7625 1400);
WIRE 16 -1 (-7475 1400)(-7625 1400);
WIRE 16 -1 (-7625 1400)(-7625 1350);
WIRE 16 -1 (-7475 1350)(-7625 1350);
WIRE 16 -1 (-7625 1350)(-7625 1300);
WIRE 16 -1 (-7475 1300)(-7625 1300);
WIRE 16 -1 (-7625 1300)(-7625 1250);
WIRE 16 -1 (-7475 1250)(-7625 1250);
WIRE 16 -1 (-7625 1250)(-7625 1200);
WIRE 16 -1 (-7475 1200)(-7625 1200);
WIRE 16 -1 (-7625 1200)(-7625 1150);
WIRE 16 -1 (-7475 1150)(-7625 1150);
WIRE 16 -1 (-7625 1150)(-7625 1100);
WIRE 16 -1 (-7475 1100)(-7625 1100);
WIRE 16 -1 (-7625 1100)(-7625 1050);
WIRE 16 -1 (-7475 1050)(-7625 1050);
WIRE 16 -1 (-7625 1050)(-7625 1000);
WIRE 16 -1 (-7475 1000)(-7625 1000);
WIRE 16 -1 (-7625 1000)(-7625 950);
WIRE 16 -1 (-7475 950)(-7625 950);
WIRE 16 -1 (-7625 950)(-7625 900);
WIRE 16 -1 (-7475 900)(-7625 900);
WIRE 16 -1 (-7625 900)(-7625 850);
WIRE 16 -1 (-7475 850)(-7625 850);
WIRE 16 -1 (-7625 850)(-7625 800);
WIRE 16 -1 (-7475 800)(-7625 800);
WIRE 16 -1 (-7625 800)(-7625 750);
WIRE 16 -1 (-7475 750)(-7625 750);
WIRE 16 -1 (-7625 750)(-7625 700);
WIRE 16 -1 (-7475 700)(-7625 700);
WIRE 16 -1 (-7625 700)(-7625 650);
WIRE 16 -1 (-7625 650)(-7475 650);
WIRE 16 -1 (-7625 650)(-7625 525);
WIRE 16 -1 (-2600 4625)(-2425 4625);
WIRE 16 -1 (-2425 4625)(-2425 4575);
WIRE 16 -1 (-2600 4575)(-2425 4575);
WIRE 16 -1 (-2425 4575)(-2425 4525);
WIRE 16 -1 (-2600 4525)(-2425 4525);
WIRE 16 -1 (-2425 4525)(-2425 4475);
WIRE 16 -1 (-2600 4475)(-2425 4475);
WIRE 16 -1 (-2425 4475)(-2425 4425);
WIRE 16 -1 (-2600 4425)(-2425 4425);
WIRE 16 -1 (-2425 4425)(-2425 4375);
WIRE 16 -1 (-2600 4375)(-2425 4375);
WIRE 16 -1 (-2425 4375)(-2425 4325);
WIRE 16 -1 (-2600 4325)(-2425 4325);
WIRE 16 -1 (-2425 4325)(-2425 4275);
WIRE 16 -1 (-2600 4275)(-2425 4275);
WIRE 16 -1 (-2425 4275)(-2425 4225);
WIRE 16 -1 (-2600 4225)(-2425 4225);
WIRE 16 -1 (-2425 4225)(-2425 4175);
WIRE 16 -1 (-2600 4175)(-2425 4175);
WIRE 16 -1 (-2425 4175)(-2425 4125);
WIRE 16 -1 (-2600 4125)(-2425 4125);
WIRE 16 -1 (-2425 4125)(-2425 4075);
WIRE 16 -1 (-2600 4075)(-2425 4075);
WIRE 16 -1 (-2425 4075)(-2425 4025);
WIRE 16 -1 (-2600 4025)(-2425 4025);
WIRE 16 -1 (-2425 4025)(-2425 3975);
WIRE 16 -1 (-2600 3975)(-2425 3975);
WIRE 16 -1 (-2425 3975)(-2425 3925);
WIRE 16 -1 (-2600 3925)(-2425 3925);
WIRE 16 -1 (-2425 3925)(-2425 3875);
WIRE 16 -1 (-2600 3875)(-2425 3875);
WIRE 16 -1 (-2425 3875)(-2425 3825);
WIRE 16 -1 (-2600 3825)(-2425 3825);
WIRE 16 -1 (-2425 3825)(-2425 3775);
WIRE 16 -1 (-2600 3775)(-2425 3775);
WIRE 16 -1 (-2425 3775)(-2425 3725);
WIRE 16 -1 (-2600 3725)(-2425 3725);
WIRE 16 -1 (-2425 3725)(-2425 3675);
WIRE 16 -1 (-2600 3675)(-2425 3675);
WIRE 16 -1 (-2425 3675)(-2425 3625);
WIRE 16 -1 (-2600 3625)(-2425 3625);
WIRE 16 -1 (-2425 3625)(-2425 3575);
WIRE 16 -1 (-2600 3575)(-2425 3575);
WIRE 16 -1 (-2425 3575)(-2425 3525);
WIRE 16 -1 (-2600 3525)(-2425 3525);
WIRE 16 -1 (-2425 3525)(-2425 3475);
WIRE 16 -1 (-2600 3475)(-2425 3475);
WIRE 16 -1 (-2425 3475)(-2425 3425);
WIRE 16 -1 (-2600 3425)(-2425 3425);
WIRE 16 -1 (-2425 3425)(-2425 3375);
WIRE 16 -1 (-2600 3375)(-2425 3375);
WIRE 16 -1 (-2425 3375)(-2425 3325);
WIRE 16 -1 (-2600 3325)(-2425 3325);
WIRE 16 -1 (-2425 3325)(-2425 3275);
WIRE 16 -1 (-2600 3275)(-2425 3275);
WIRE 16 -1 (-2425 3275)(-2425 3225);
WIRE 16 -1 (-2600 3225)(-2425 3225);
WIRE 16 -1 (-2425 3225)(-2425 3175);
WIRE 16 -1 (-2600 3175)(-2425 3175);
WIRE 16 -1 (-2425 3175)(-2425 3125);
WIRE 16 -1 (-2600 3125)(-2425 3125);
WIRE 16 -1 (-2425 3125)(-2425 3075);
WIRE 16 -1 (-2600 3075)(-2425 3075);
WIRE 16 -1 (-2425 3075)(-2425 3025);
WIRE 16 -1 (-2600 3025)(-2425 3025);
WIRE 16 -1 (-2425 3025)(-2425 2975);
WIRE 16 -1 (-2600 2975)(-2425 2975);
WIRE 16 -1 (-2425 2975)(-2425 2925);
WIRE 16 -1 (-2600 2925)(-2425 2925);
WIRE 16 -1 (-2425 2925)(-2425 2875);
WIRE 16 -1 (-2600 2875)(-2425 2875);
WIRE 16 -1 (-2425 2875)(-2425 2825);
WIRE 16 -1 (-2600 2825)(-2425 2825);
WIRE 16 -1 (-2425 2825)(-2425 2775);
WIRE 16 -1 (-2600 2775)(-2425 2775);
WIRE 16 -1 (-2425 2775)(-2425 2725);
WIRE 16 -1 (-2600 2725)(-2425 2725);
WIRE 16 -1 (-2425 2725)(-2425 2675);
WIRE 16 -1 (-2600 2675)(-2425 2675);
WIRE 16 -1 (-2425 2675)(-2425 2625);
WIRE 16 -1 (-2600 2625)(-2425 2625);
WIRE 16 -1 (-2425 2625)(-2425 2575);
WIRE 16 -1 (-2600 2575)(-2425 2575);
WIRE 16 -1 (-2425 2575)(-2425 2525);
WIRE 16 -1 (-2600 2525)(-2425 2525);
WIRE 16 -1 (-2425 2525)(-2425 2475);
WIRE 16 -1 (-2600 2475)(-2425 2475);
WIRE 16 -1 (-2425 2475)(-2425 2425);
WIRE 16 -1 (-2600 2425)(-2425 2425);
WIRE 16 -1 (-2425 2425)(-2425 2375);
WIRE 16 -1 (-2600 2375)(-2425 2375);
WIRE 16 -1 (-2425 2375)(-2425 2325);
WIRE 16 -1 (-2600 2325)(-2425 2325);
WIRE 16 -1 (-2425 2325)(-2425 2275);
WIRE 16 -1 (-2600 2275)(-2425 2275);
WIRE 16 -1 (-2425 2275)(-2425 2225);
WIRE 16 -1 (-2600 2225)(-2425 2225);
WIRE 16 -1 (-2425 2225)(-2425 2175);
WIRE 16 -1 (-2600 2175)(-2425 2175);
WIRE 16 -1 (-2425 2175)(-2425 2125);
WIRE 16 -1 (-2600 2125)(-2425 2125);
WIRE 16 -1 (-2425 2125)(-2425 2075);
WIRE 16 -1 (-2600 2075)(-2425 2075);
WIRE 16 -1 (-2425 2075)(-2425 2025);
WIRE 16 -1 (-2600 2025)(-2425 2025);
WIRE 16 -1 (-2425 2025)(-2425 1975);
WIRE 16 -1 (-2600 1975)(-2425 1975);
WIRE 16 -1 (-2425 1975)(-2425 1925);
WIRE 16 -1 (-2600 1925)(-2425 1925);
WIRE 16 -1 (-2425 1925)(-2425 1875);
WIRE 16 -1 (-2600 1875)(-2425 1875);
WIRE 16 -1 (-2425 1875)(-2425 1825);
WIRE 16 -1 (-2600 1825)(-2425 1825);
WIRE 16 -1 (-2425 1825)(-2425 1775);
WIRE 16 -1 (-2600 1775)(-2425 1775);
WIRE 16 -1 (-2425 1775)(-2425 1725);
WIRE 16 -1 (-2600 1725)(-2425 1725);
WIRE 16 -1 (-2425 1725)(-2425 1675);
WIRE 16 -1 (-2600 1675)(-2425 1675);
WIRE 16 -1 (-2425 1675)(-2425 1625);
WIRE 16 -1 (-2600 1625)(-2425 1625);
WIRE 16 -1 (-2425 1625)(-2425 1575);
WIRE 16 -1 (-2600 1575)(-2425 1575);
WIRE 16 -1 (-2425 1575)(-2425 1525);
WIRE 16 -1 (-2600 1525)(-2425 1525);
WIRE 16 -1 (-2425 1525)(-2425 1475);
WIRE 16 -1 (-2600 1475)(-2425 1475);
WIRE 16 -1 (-2425 1475)(-2425 1425);
WIRE 16 -1 (-2600 1425)(-2425 1425);
WIRE 16 -1 (-2425 1425)(-2425 1375);
WIRE 16 -1 (-2600 1375)(-2425 1375);
WIRE 16 -1 (-2425 1375)(-2425 1325);
WIRE 16 -1 (-2600 1325)(-2425 1325);
WIRE 16 -1 (-2425 1325)(-2425 1275);
WIRE 16 -1 (-2600 1275)(-2425 1275);
WIRE 16 -1 (-2425 1275)(-2425 1225);
WIRE 16 -1 (-2600 1225)(-2425 1225);
WIRE 16 -1 (-2425 1225)(-2425 1175);
WIRE 16 -1 (-2600 1175)(-2425 1175);
WIRE 16 -1 (-2425 1175)(-2425 1125);
WIRE 16 -1 (-2600 1125)(-2425 1125);
WIRE 16 -1 (-2425 1125)(-2425 1075);
WIRE 16 -1 (-2600 1075)(-2425 1075);
WIRE 16 -1 (-2425 1075)(-2425 1025);
WIRE 16 -1 (-2600 1025)(-2425 1025);
WIRE 16 -1 (-2425 1025)(-2425 975);
WIRE 16 -1 (-2600 975)(-2425 975);
WIRE 16 -1 (-2425 975)(-2425 925);
WIRE 16 -1 (-2600 925)(-2425 925);
WIRE 16 -1 (-2425 925)(-2425 875);
WIRE 16 -1 (-2600 875)(-2425 875);
WIRE 16 -1 (-2425 875)(-2425 825);
WIRE 16 -1 (-2600 825)(-2425 825);
WIRE 16 -1 (-2425 825)(-2425 775);
WIRE 16 -1 (-2600 775)(-2425 775);
WIRE 16 -1 (-2425 775)(-2425 725);
WIRE 16 -1 (-2600 725)(-2425 725);
WIRE 16 -1 (-2425 725)(-2425 675);
WIRE 16 -1 (-2600 675)(-2425 675);
WIRE 16 -1 (-2425 675)(-2425 550);
WIRE 16 -1 (-2025 4600)(-1875 4600);
WIRE 16 -1 (-2025 4600)(-2025 4550);
WIRE 16 -1 (-1875 4550)(-2025 4550);
WIRE 16 -1 (-2025 4550)(-2025 4500);
WIRE 16 -1 (-1875 4500)(-2025 4500);
WIRE 16 -1 (-2025 4500)(-2025 4450);
WIRE 16 -1 (-1875 4450)(-2025 4450);
WIRE 16 -1 (-2025 4450)(-2025 4400);
WIRE 16 -1 (-1875 4400)(-2025 4400);
WIRE 16 -1 (-2025 4400)(-2025 4350);
WIRE 16 -1 (-1875 4350)(-2025 4350);
WIRE 16 -1 (-2025 4350)(-2025 4300);
WIRE 16 -1 (-1875 4300)(-2025 4300);
WIRE 16 -1 (-2025 4300)(-2025 4250);
WIRE 16 -1 (-1875 4250)(-2025 4250);
WIRE 16 -1 (-2025 4250)(-2025 4200);
WIRE 16 -1 (-1875 4200)(-2025 4200);
WIRE 16 -1 (-2025 4200)(-2025 4150);
WIRE 16 -1 (-1875 4150)(-2025 4150);
WIRE 16 -1 (-2025 4150)(-2025 4100);
WIRE 16 -1 (-1875 4100)(-2025 4100);
WIRE 16 -1 (-2025 4100)(-2025 4050);
WIRE 16 -1 (-1875 4050)(-2025 4050);
WIRE 16 -1 (-2025 4050)(-2025 4000);
WIRE 16 -1 (-1875 4000)(-2025 4000);
WIRE 16 -1 (-2025 4000)(-2025 3950);
WIRE 16 -1 (-1875 3950)(-2025 3950);
WIRE 16 -1 (-2025 3950)(-2025 3900);
WIRE 16 -1 (-1875 3900)(-2025 3900);
WIRE 16 -1 (-2025 3900)(-2025 3850);
WIRE 16 -1 (-1875 3850)(-2025 3850);
WIRE 16 -1 (-2025 3850)(-2025 3800);
WIRE 16 -1 (-1875 3800)(-2025 3800);
WIRE 16 -1 (-2025 3800)(-2025 3750);
WIRE 16 -1 (-1875 3750)(-2025 3750);
WIRE 16 -1 (-2025 3750)(-2025 3700);
WIRE 16 -1 (-1875 3700)(-2025 3700);
WIRE 16 -1 (-2025 3700)(-2025 3650);
WIRE 16 -1 (-1875 3650)(-2025 3650);
WIRE 16 -1 (-2025 3650)(-2025 3600);
WIRE 16 -1 (-1875 3600)(-2025 3600);
WIRE 16 -1 (-2025 3600)(-2025 3550);
WIRE 16 -1 (-1875 3550)(-2025 3550);
WIRE 16 -1 (-2025 3550)(-2025 3500);
WIRE 16 -1 (-1875 3500)(-2025 3500);
WIRE 16 -1 (-2025 3500)(-2025 3450);
WIRE 16 -1 (-1875 3450)(-2025 3450);
WIRE 16 -1 (-2025 3450)(-2025 3400);
WIRE 16 -1 (-1875 3400)(-2025 3400);
WIRE 16 -1 (-2025 3400)(-2025 3350);
WIRE 16 -1 (-1875 3350)(-2025 3350);
WIRE 16 -1 (-2025 3350)(-2025 3300);
WIRE 16 -1 (-1875 3300)(-2025 3300);
WIRE 16 -1 (-2025 3300)(-2025 3250);
WIRE 16 -1 (-1875 3250)(-2025 3250);
WIRE 16 -1 (-2025 3250)(-2025 3200);
WIRE 16 -1 (-1875 3200)(-2025 3200);
WIRE 16 -1 (-2025 3200)(-2025 3150);
WIRE 16 -1 (-1875 3150)(-2025 3150);
WIRE 16 -1 (-2025 3150)(-2025 3100);
WIRE 16 -1 (-1875 3100)(-2025 3100);
WIRE 16 -1 (-2025 3100)(-2025 3050);
WIRE 16 -1 (-1875 3050)(-2025 3050);
WIRE 16 -1 (-2025 3050)(-2025 3000);
WIRE 16 -1 (-1875 3000)(-2025 3000);
WIRE 16 -1 (-2025 3000)(-2025 2950);
WIRE 16 -1 (-1875 2950)(-2025 2950);
WIRE 16 -1 (-2025 2950)(-2025 2900);
WIRE 16 -1 (-1875 2900)(-2025 2900);
WIRE 16 -1 (-2025 2900)(-2025 2850);
WIRE 16 -1 (-1875 2850)(-2025 2850);
WIRE 16 -1 (-2025 2850)(-2025 2800);
WIRE 16 -1 (-1875 2800)(-2025 2800);
WIRE 16 -1 (-2025 2800)(-2025 2750);
WIRE 16 -1 (-1875 2750)(-2025 2750);
WIRE 16 -1 (-2025 2750)(-2025 2700);
WIRE 16 -1 (-1875 2700)(-2025 2700);
WIRE 16 -1 (-2025 2700)(-2025 2650);
WIRE 16 -1 (-1875 2650)(-2025 2650);
WIRE 16 -1 (-2025 2650)(-2025 2600);
WIRE 16 -1 (-1875 2600)(-2025 2600);
WIRE 16 -1 (-2025 2600)(-2025 2550);
WIRE 16 -1 (-1875 2550)(-2025 2550);
WIRE 16 -1 (-2025 2550)(-2025 2500);
WIRE 16 -1 (-1875 2500)(-2025 2500);
WIRE 16 -1 (-2025 2500)(-2025 2450);
WIRE 16 -1 (-1875 2450)(-2025 2450);
WIRE 16 -1 (-2025 2450)(-2025 2400);
WIRE 16 -1 (-1875 2400)(-2025 2400);
WIRE 16 -1 (-2025 2400)(-2025 2350);
WIRE 16 -1 (-1875 2350)(-2025 2350);
WIRE 16 -1 (-2025 2350)(-2025 2300);
WIRE 16 -1 (-1875 2300)(-2025 2300);
WIRE 16 -1 (-2025 2300)(-2025 2250);
WIRE 16 -1 (-1875 2250)(-2025 2250);
WIRE 16 -1 (-2025 2250)(-2025 2200);
WIRE 16 -1 (-1875 2200)(-2025 2200);
WIRE 16 -1 (-2025 2200)(-2025 2150);
WIRE 16 -1 (-1875 2150)(-2025 2150);
WIRE 16 -1 (-2025 2150)(-2025 2100);
WIRE 16 -1 (-1875 2100)(-2025 2100);
WIRE 16 -1 (-2025 2100)(-2025 2050);
WIRE 16 -1 (-1875 2050)(-2025 2050);
WIRE 16 -1 (-2025 2050)(-2025 2000);
WIRE 16 -1 (-1875 2000)(-2025 2000);
WIRE 16 -1 (-2025 2000)(-2025 1950);
WIRE 16 -1 (-1875 1950)(-2025 1950);
WIRE 16 -1 (-2025 1950)(-2025 1900);
WIRE 16 -1 (-1875 1900)(-2025 1900);
WIRE 16 -1 (-2025 1900)(-2025 1850);
WIRE 16 -1 (-1875 1850)(-2025 1850);
WIRE 16 -1 (-2025 1850)(-2025 1800);
WIRE 16 -1 (-1875 1800)(-2025 1800);
WIRE 16 -1 (-2025 1800)(-2025 1750);
WIRE 16 -1 (-1875 1750)(-2025 1750);
WIRE 16 -1 (-2025 1750)(-2025 1700);
WIRE 16 -1 (-1875 1700)(-2025 1700);
WIRE 16 -1 (-2025 1700)(-2025 1650);
WIRE 16 -1 (-1875 1650)(-2025 1650);
WIRE 16 -1 (-2025 1650)(-2025 1600);
WIRE 16 -1 (-1875 1600)(-2025 1600);
WIRE 16 -1 (-2025 1600)(-2025 1550);
WIRE 16 -1 (-1875 1550)(-2025 1550);
WIRE 16 -1 (-2025 1550)(-2025 1500);
WIRE 16 -1 (-1875 1500)(-2025 1500);
WIRE 16 -1 (-2025 1500)(-2025 1450);
WIRE 16 -1 (-1875 1450)(-2025 1450);
WIRE 16 -1 (-2025 1450)(-2025 1400);
WIRE 16 -1 (-1875 1400)(-2025 1400);
WIRE 16 -1 (-2025 1400)(-2025 1350);
WIRE 16 -1 (-1875 1350)(-2025 1350);
WIRE 16 -1 (-2025 1350)(-2025 1300);
WIRE 16 -1 (-1875 1300)(-2025 1300);
WIRE 16 -1 (-2025 1300)(-2025 1250);
WIRE 16 -1 (-1875 1250)(-2025 1250);
WIRE 16 -1 (-2025 1250)(-2025 1200);
WIRE 16 -1 (-1875 1200)(-2025 1200);
WIRE 16 -1 (-2025 1200)(-2025 1150);
WIRE 16 -1 (-1875 1150)(-2025 1150);
WIRE 16 -1 (-2025 1150)(-2025 1100);
WIRE 16 -1 (-1875 1100)(-2025 1100);
WIRE 16 -1 (-2025 1100)(-2025 1050);
WIRE 16 -1 (-1875 1050)(-2025 1050);
WIRE 16 -1 (-2025 1050)(-2025 1000);
WIRE 16 -1 (-1875 1000)(-2025 1000);
WIRE 16 -1 (-2025 1000)(-2025 950);
WIRE 16 -1 (-1875 950)(-2025 950);
WIRE 16 -1 (-2025 950)(-2025 900);
WIRE 16 -1 (-1875 900)(-2025 900);
WIRE 16 -1 (-2025 900)(-2025 850);
WIRE 16 -1 (-1875 850)(-2025 850);
WIRE 16 -1 (-2025 850)(-2025 800);
WIRE 16 -1 (-1875 800)(-2025 800);
WIRE 16 -1 (-2025 800)(-2025 750);
WIRE 16 -1 (-1875 750)(-2025 750);
WIRE 16 -1 (-2025 750)(-2025 700);
WIRE 16 -1 (-1875 700)(-2025 700);
WIRE 16 -1 (-2025 700)(-2025 650);
WIRE 16 -1 (-2025 650)(-1875 650);
WIRE 16 -1 (-2025 650)(-2025 525);
WIRE 16 -1 (-675 4600)(-500 4600);
WIRE 16 -1 (-500 4600)(-500 4550);
WIRE 16 -1 (-675 4550)(-500 4550);
WIRE 16 -1 (-500 4550)(-500 4500);
WIRE 16 -1 (-675 4500)(-500 4500);
WIRE 16 -1 (-500 4500)(-500 4450);
WIRE 16 -1 (-675 4450)(-500 4450);
WIRE 16 -1 (-500 4450)(-500 4400);
WIRE 16 -1 (-675 4400)(-500 4400);
WIRE 16 -1 (-500 4400)(-500 4350);
WIRE 16 -1 (-675 4350)(-500 4350);
WIRE 16 -1 (-500 4350)(-500 4300);
WIRE 16 -1 (-675 4300)(-500 4300);
WIRE 16 -1 (-500 4300)(-500 4250);
WIRE 16 -1 (-675 4250)(-500 4250);
WIRE 16 -1 (-500 4250)(-500 4200);
WIRE 16 -1 (-675 4200)(-500 4200);
WIRE 16 -1 (-500 4200)(-500 4150);
WIRE 16 -1 (-675 4150)(-500 4150);
WIRE 16 -1 (-500 4150)(-500 4100);
WIRE 16 -1 (-675 4100)(-500 4100);
WIRE 16 -1 (-500 4100)(-500 4050);
WIRE 16 -1 (-675 4050)(-500 4050);
WIRE 16 -1 (-500 4050)(-500 4000);
WIRE 16 -1 (-675 4000)(-500 4000);
WIRE 16 -1 (-500 4000)(-500 3950);
WIRE 16 -1 (-675 3950)(-500 3950);
WIRE 16 -1 (-500 3950)(-500 3900);
WIRE 16 -1 (-675 3900)(-500 3900);
WIRE 16 -1 (-500 3900)(-500 3850);
WIRE 16 -1 (-675 3850)(-500 3850);
WIRE 16 -1 (-500 3850)(-500 3800);
WIRE 16 -1 (-675 3800)(-500 3800);
WIRE 16 -1 (-500 3800)(-500 3750);
WIRE 16 -1 (-675 3750)(-500 3750);
WIRE 16 -1 (-500 3750)(-500 3700);
WIRE 16 -1 (-675 3700)(-500 3700);
WIRE 16 -1 (-500 3700)(-500 3650);
WIRE 16 -1 (-675 3650)(-500 3650);
WIRE 16 -1 (-500 3650)(-500 3600);
WIRE 16 -1 (-675 3600)(-500 3600);
WIRE 16 -1 (-500 3600)(-500 3550);
WIRE 16 -1 (-675 3550)(-500 3550);
WIRE 16 -1 (-500 3550)(-500 3500);
WIRE 16 -1 (-675 3500)(-500 3500);
WIRE 16 -1 (-500 3500)(-500 3450);
WIRE 16 -1 (-675 3450)(-500 3450);
WIRE 16 -1 (-500 3450)(-500 3400);
WIRE 16 -1 (-675 3400)(-500 3400);
WIRE 16 -1 (-500 3400)(-500 3350);
WIRE 16 -1 (-675 3350)(-500 3350);
WIRE 16 -1 (-500 3350)(-500 3300);
WIRE 16 -1 (-675 3300)(-500 3300);
WIRE 16 -1 (-500 3300)(-500 3250);
WIRE 16 -1 (-675 3250)(-500 3250);
WIRE 16 -1 (-500 3250)(-500 3200);
WIRE 16 -1 (-675 3200)(-500 3200);
WIRE 16 -1 (-500 3200)(-500 3150);
WIRE 16 -1 (-675 3150)(-500 3150);
WIRE 16 -1 (-500 3150)(-500 3100);
WIRE 16 -1 (-675 3100)(-500 3100);
WIRE 16 -1 (-500 3100)(-500 3050);
WIRE 16 -1 (-675 3050)(-500 3050);
WIRE 16 -1 (-500 3050)(-500 3000);
WIRE 16 -1 (-675 3000)(-500 3000);
WIRE 16 -1 (-500 3000)(-500 2950);
WIRE 16 -1 (-675 2950)(-500 2950);
WIRE 16 -1 (-500 2950)(-500 2900);
WIRE 16 -1 (-675 2900)(-500 2900);
WIRE 16 -1 (-500 2900)(-500 2850);
WIRE 16 -1 (-675 2850)(-500 2850);
WIRE 16 -1 (-500 2850)(-500 2800);
WIRE 16 -1 (-675 2800)(-500 2800);
WIRE 16 -1 (-500 2800)(-500 2750);
WIRE 16 -1 (-675 2750)(-500 2750);
WIRE 16 -1 (-500 2750)(-500 2700);
WIRE 16 -1 (-675 2700)(-500 2700);
WIRE 16 -1 (-500 2700)(-500 2650);
WIRE 16 -1 (-675 2650)(-500 2650);
WIRE 16 -1 (-500 2650)(-500 2600);
WIRE 16 -1 (-675 2600)(-500 2600);
WIRE 16 -1 (-500 2600)(-500 2550);
WIRE 16 -1 (-675 2550)(-500 2550);
WIRE 16 -1 (-500 2550)(-500 2500);
WIRE 16 -1 (-675 2500)(-500 2500);
WIRE 16 -1 (-500 2500)(-500 2450);
WIRE 16 -1 (-675 2450)(-500 2450);
WIRE 16 -1 (-500 2450)(-500 2400);
WIRE 16 -1 (-675 2400)(-500 2400);
WIRE 16 -1 (-500 2400)(-500 2350);
WIRE 16 -1 (-675 2350)(-500 2350);
WIRE 16 -1 (-500 2350)(-500 2300);
WIRE 16 -1 (-675 2300)(-500 2300);
WIRE 16 -1 (-500 2300)(-500 2250);
WIRE 16 -1 (-675 2250)(-500 2250);
WIRE 16 -1 (-500 2250)(-500 2200);
WIRE 16 -1 (-675 2200)(-500 2200);
WIRE 16 -1 (-500 2200)(-500 2150);
WIRE 16 -1 (-675 2150)(-500 2150);
WIRE 16 -1 (-500 2150)(-500 2100);
WIRE 16 -1 (-675 2100)(-500 2100);
WIRE 16 -1 (-500 2100)(-500 2050);
WIRE 16 -1 (-675 2050)(-500 2050);
WIRE 16 -1 (-500 2050)(-500 2000);
WIRE 16 -1 (-675 2000)(-500 2000);
WIRE 16 -1 (-500 2000)(-500 1950);
WIRE 16 -1 (-675 1950)(-500 1950);
WIRE 16 -1 (-500 1950)(-500 1900);
WIRE 16 -1 (-675 1900)(-500 1900);
WIRE 16 -1 (-500 1900)(-500 1850);
WIRE 16 -1 (-675 1850)(-500 1850);
WIRE 16 -1 (-500 1850)(-500 1800);
WIRE 16 -1 (-675 1800)(-500 1800);
WIRE 16 -1 (-500 1800)(-500 1750);
WIRE 16 -1 (-675 1750)(-500 1750);
WIRE 16 -1 (-500 1750)(-500 1700);
WIRE 16 -1 (-675 1700)(-500 1700);
WIRE 16 -1 (-500 1700)(-500 1650);
WIRE 16 -1 (-675 1650)(-500 1650);
WIRE 16 -1 (-500 1650)(-500 1600);
WIRE 16 -1 (-675 1600)(-500 1600);
WIRE 16 -1 (-500 1600)(-500 1550);
WIRE 16 -1 (-675 1550)(-500 1550);
WIRE 16 -1 (-500 1550)(-500 1500);
WIRE 16 -1 (-675 1500)(-500 1500);
WIRE 16 -1 (-500 1500)(-500 1450);
WIRE 16 -1 (-675 1450)(-500 1450);
WIRE 16 -1 (-500 1450)(-500 1400);
WIRE 16 -1 (-675 1400)(-500 1400);
WIRE 16 -1 (-500 1400)(-500 1350);
WIRE 16 -1 (-675 1350)(-500 1350);
WIRE 16 -1 (-500 1350)(-500 1300);
WIRE 16 -1 (-675 1300)(-500 1300);
WIRE 16 -1 (-500 1300)(-500 1250);
WIRE 16 -1 (-675 1250)(-500 1250);
WIRE 16 -1 (-500 1250)(-500 1200);
WIRE 16 -1 (-675 1200)(-500 1200);
WIRE 16 -1 (-500 1200)(-500 1150);
WIRE 16 -1 (-675 1150)(-500 1150);
WIRE 16 -1 (-500 1150)(-500 1100);
WIRE 16 -1 (-675 1100)(-500 1100);
WIRE 16 -1 (-500 1100)(-500 1050);
WIRE 16 -1 (-675 1050)(-500 1050);
WIRE 16 -1 (-500 1050)(-500 1000);
WIRE 16 -1 (-675 1000)(-500 1000);
WIRE 16 -1 (-500 1000)(-500 950);
WIRE 16 -1 (-675 950)(-500 950);
WIRE 16 -1 (-500 950)(-500 900);
WIRE 16 -1 (-675 900)(-500 900);
WIRE 16 -1 (-500 900)(-500 850);
WIRE 16 -1 (-675 850)(-500 850);
WIRE 16 -1 (-500 850)(-500 800);
WIRE 16 -1 (-675 800)(-500 800);
WIRE 16 -1 (-500 800)(-500 750);
WIRE 16 -1 (-675 750)(-500 750);
WIRE 16 -1 (-500 750)(-500 700);
WIRE 16 -1 (-675 700)(-500 700);
WIRE 16 -1 (-500 700)(-500 650);
WIRE 16 -1 (-675 650)(-500 650);
WIRE 16 -1 (-500 650)(-500 525);
WIRE 16 -1 (-6275 4600)(-6100 4600);
WIRE 16 -1 (-6100 4600)(-6100 4550);
WIRE 16 -1 (-6275 4550)(-6100 4550);
WIRE 16 -1 (-6100 4550)(-6100 4500);
WIRE 16 -1 (-6275 4500)(-6100 4500);
WIRE 16 -1 (-6100 4500)(-6100 4450);
WIRE 16 -1 (-6275 4450)(-6100 4450);
WIRE 16 -1 (-6100 4450)(-6100 4400);
WIRE 16 -1 (-6275 4400)(-6100 4400);
WIRE 16 -1 (-6100 4400)(-6100 4350);
WIRE 16 -1 (-6275 4350)(-6100 4350);
WIRE 16 -1 (-6100 4350)(-6100 4300);
WIRE 16 -1 (-6275 4300)(-6100 4300);
WIRE 16 -1 (-6100 4300)(-6100 4250);
WIRE 16 -1 (-6275 4250)(-6100 4250);
WIRE 16 -1 (-6100 4250)(-6100 4200);
WIRE 16 -1 (-6275 4200)(-6100 4200);
WIRE 16 -1 (-6100 4200)(-6100 4150);
WIRE 16 -1 (-6275 4150)(-6100 4150);
WIRE 16 -1 (-6100 4150)(-6100 4100);
WIRE 16 -1 (-6275 4100)(-6100 4100);
WIRE 16 -1 (-6100 4100)(-6100 4050);
WIRE 16 -1 (-6275 4050)(-6100 4050);
WIRE 16 -1 (-6100 4050)(-6100 4000);
WIRE 16 -1 (-6275 4000)(-6100 4000);
WIRE 16 -1 (-6100 4000)(-6100 3950);
WIRE 16 -1 (-6275 3950)(-6100 3950);
WIRE 16 -1 (-6100 3950)(-6100 3900);
WIRE 16 -1 (-6275 3900)(-6100 3900);
WIRE 16 -1 (-6100 3900)(-6100 3850);
WIRE 16 -1 (-6275 3850)(-6100 3850);
WIRE 16 -1 (-6100 3850)(-6100 3800);
WIRE 16 -1 (-6275 3800)(-6100 3800);
WIRE 16 -1 (-6100 3800)(-6100 3750);
WIRE 16 -1 (-6275 3750)(-6100 3750);
WIRE 16 -1 (-6100 3750)(-6100 3700);
WIRE 16 -1 (-6275 3700)(-6100 3700);
WIRE 16 -1 (-6100 3700)(-6100 3650);
WIRE 16 -1 (-6275 3650)(-6100 3650);
WIRE 16 -1 (-6100 3650)(-6100 3600);
WIRE 16 -1 (-6275 3600)(-6100 3600);
WIRE 16 -1 (-6100 3600)(-6100 3550);
WIRE 16 -1 (-6275 3550)(-6100 3550);
WIRE 16 -1 (-6100 3550)(-6100 3500);
WIRE 16 -1 (-6275 3500)(-6100 3500);
WIRE 16 -1 (-6100 3500)(-6100 3450);
WIRE 16 -1 (-6275 3450)(-6100 3450);
WIRE 16 -1 (-6100 3450)(-6100 3400);
WIRE 16 -1 (-6275 3400)(-6100 3400);
WIRE 16 -1 (-6100 3400)(-6100 3350);
WIRE 16 -1 (-6275 3350)(-6100 3350);
WIRE 16 -1 (-6100 3350)(-6100 3300);
WIRE 16 -1 (-6275 3300)(-6100 3300);
WIRE 16 -1 (-6100 3300)(-6100 3250);
WIRE 16 -1 (-6275 3250)(-6100 3250);
WIRE 16 -1 (-6100 3250)(-6100 3200);
WIRE 16 -1 (-6275 3200)(-6100 3200);
WIRE 16 -1 (-6100 3200)(-6100 3150);
WIRE 16 -1 (-6275 3150)(-6100 3150);
WIRE 16 -1 (-6100 3150)(-6100 3100);
WIRE 16 -1 (-6275 3100)(-6100 3100);
WIRE 16 -1 (-6100 3100)(-6100 3050);
WIRE 16 -1 (-6275 3050)(-6100 3050);
WIRE 16 -1 (-6100 3050)(-6100 3000);
WIRE 16 -1 (-6275 3000)(-6100 3000);
WIRE 16 -1 (-6100 3000)(-6100 2950);
WIRE 16 -1 (-6275 2950)(-6100 2950);
WIRE 16 -1 (-6100 2950)(-6100 2900);
WIRE 16 -1 (-6275 2900)(-6100 2900);
WIRE 16 -1 (-6100 2900)(-6100 2850);
WIRE 16 -1 (-6275 2850)(-6100 2850);
WIRE 16 -1 (-6100 2850)(-6100 2800);
WIRE 16 -1 (-6275 2800)(-6100 2800);
WIRE 16 -1 (-6100 2800)(-6100 2750);
WIRE 16 -1 (-6275 2750)(-6100 2750);
WIRE 16 -1 (-6100 2750)(-6100 2700);
WIRE 16 -1 (-6275 2700)(-6100 2700);
WIRE 16 -1 (-6100 2700)(-6100 2650);
WIRE 16 -1 (-6275 2650)(-6100 2650);
WIRE 16 -1 (-6100 2650)(-6100 2600);
WIRE 16 -1 (-6275 2600)(-6100 2600);
WIRE 16 -1 (-6100 2600)(-6100 2550);
WIRE 16 -1 (-6275 2550)(-6100 2550);
WIRE 16 -1 (-6100 2550)(-6100 2500);
WIRE 16 -1 (-6275 2500)(-6100 2500);
WIRE 16 -1 (-6100 2500)(-6100 2450);
WIRE 16 -1 (-6275 2450)(-6100 2450);
WIRE 16 -1 (-6100 2450)(-6100 2400);
WIRE 16 -1 (-6275 2400)(-6100 2400);
WIRE 16 -1 (-6100 2400)(-6100 2350);
WIRE 16 -1 (-6275 2350)(-6100 2350);
WIRE 16 -1 (-6100 2350)(-6100 2300);
WIRE 16 -1 (-6275 2300)(-6100 2300);
WIRE 16 -1 (-6100 2300)(-6100 2250);
WIRE 16 -1 (-6275 2250)(-6100 2250);
WIRE 16 -1 (-6100 2250)(-6100 2200);
WIRE 16 -1 (-6275 2200)(-6100 2200);
WIRE 16 -1 (-6100 2200)(-6100 2150);
WIRE 16 -1 (-6275 2150)(-6100 2150);
WIRE 16 -1 (-6100 2150)(-6100 2100);
WIRE 16 -1 (-6275 2100)(-6100 2100);
WIRE 16 -1 (-6100 2100)(-6100 2050);
WIRE 16 -1 (-6275 2050)(-6100 2050);
WIRE 16 -1 (-6100 2050)(-6100 2000);
WIRE 16 -1 (-6275 2000)(-6100 2000);
WIRE 16 -1 (-6100 2000)(-6100 1950);
WIRE 16 -1 (-6275 1950)(-6100 1950);
WIRE 16 -1 (-6100 1950)(-6100 1900);
WIRE 16 -1 (-6275 1900)(-6100 1900);
WIRE 16 -1 (-6100 1900)(-6100 1850);
WIRE 16 -1 (-6275 1850)(-6100 1850);
WIRE 16 -1 (-6100 1850)(-6100 1800);
WIRE 16 -1 (-6275 1800)(-6100 1800);
WIRE 16 -1 (-6100 1800)(-6100 1750);
WIRE 16 -1 (-6275 1750)(-6100 1750);
WIRE 16 -1 (-6100 1750)(-6100 1700);
WIRE 16 -1 (-6275 1700)(-6100 1700);
WIRE 16 -1 (-6100 1700)(-6100 1650);
WIRE 16 -1 (-6275 1650)(-6100 1650);
WIRE 16 -1 (-6100 1650)(-6100 1600);
WIRE 16 -1 (-6275 1600)(-6100 1600);
WIRE 16 -1 (-6100 1600)(-6100 1550);
WIRE 16 -1 (-6275 1550)(-6100 1550);
WIRE 16 -1 (-6100 1550)(-6100 1500);
WIRE 16 -1 (-6275 1500)(-6100 1500);
WIRE 16 -1 (-6100 1500)(-6100 1450);
WIRE 16 -1 (-6275 1450)(-6100 1450);
WIRE 16 -1 (-6100 1450)(-6100 1400);
WIRE 16 -1 (-6275 1400)(-6100 1400);
WIRE 16 -1 (-6100 1400)(-6100 1350);
WIRE 16 -1 (-6275 1350)(-6100 1350);
WIRE 16 -1 (-6100 1350)(-6100 1300);
WIRE 16 -1 (-6275 1300)(-6100 1300);
WIRE 16 -1 (-6100 1300)(-6100 1250);
WIRE 16 -1 (-6275 1250)(-6100 1250);
WIRE 16 -1 (-6100 1250)(-6100 1200);
WIRE 16 -1 (-6275 1200)(-6100 1200);
WIRE 16 -1 (-6100 1200)(-6100 1150);
WIRE 16 -1 (-6275 1150)(-6100 1150);
WIRE 16 -1 (-6100 1150)(-6100 1100);
WIRE 16 -1 (-6275 1100)(-6100 1100);
WIRE 16 -1 (-6100 1100)(-6100 1050);
WIRE 16 -1 (-6275 1050)(-6100 1050);
WIRE 16 -1 (-6100 1050)(-6100 1000);
WIRE 16 -1 (-6275 1000)(-6100 1000);
WIRE 16 -1 (-6100 1000)(-6100 950);
WIRE 16 -1 (-6275 950)(-6100 950);
WIRE 16 -1 (-6100 950)(-6100 900);
WIRE 16 -1 (-6275 900)(-6100 900);
WIRE 16 -1 (-6100 900)(-6100 850);
WIRE 16 -1 (-6275 850)(-6100 850);
WIRE 16 -1 (-6100 850)(-6100 800);
WIRE 16 -1 (-6275 800)(-6100 800);
WIRE 16 -1 (-6100 800)(-6100 750);
WIRE 16 -1 (-6275 750)(-6100 750);
WIRE 16 -1 (-6100 750)(-6100 700);
WIRE 16 -1 (-6275 700)(-6100 700);
WIRE 16 -1 (-6100 700)(-6100 650);
WIRE 16 -1 (-6275 650)(-6100 650);
WIRE 16 -1 (-6100 650)(-6100 525);
WIRE 16 -1 (-5775 4625)(-5625 4625);
WIRE 16 -1 (-5775 4575)(-5775 4625);
WIRE 16 -1 (-5625 4575)(-5775 4575);
WIRE 16 -1 (-5775 4575)(-5775 4525);
WIRE 16 -1 (-5625 4525)(-5775 4525);
WIRE 16 -1 (-5775 4525)(-5775 4475);
WIRE 16 -1 (-5625 4475)(-5775 4475);
WIRE 16 -1 (-5775 4475)(-5775 4425);
WIRE 16 -1 (-5625 4425)(-5775 4425);
WIRE 16 -1 (-5775 4425)(-5775 4375);
WIRE 16 -1 (-5625 4375)(-5775 4375);
WIRE 16 -1 (-5775 4375)(-5775 4325);
WIRE 16 -1 (-5625 4325)(-5775 4325);
WIRE 16 -1 (-5775 4325)(-5775 4275);
WIRE 16 -1 (-5625 4275)(-5775 4275);
WIRE 16 -1 (-5775 4275)(-5775 4225);
WIRE 16 -1 (-5625 4225)(-5775 4225);
WIRE 16 -1 (-5775 4225)(-5775 4175);
WIRE 16 -1 (-5625 4175)(-5775 4175);
WIRE 16 -1 (-5775 4175)(-5775 4125);
WIRE 16 -1 (-5625 4125)(-5775 4125);
WIRE 16 -1 (-5775 4125)(-5775 4075);
WIRE 16 -1 (-5625 4075)(-5775 4075);
WIRE 16 -1 (-5775 4075)(-5775 4025);
WIRE 16 -1 (-5625 4025)(-5775 4025);
WIRE 16 -1 (-5775 4025)(-5775 3975);
WIRE 16 -1 (-5625 3975)(-5775 3975);
WIRE 16 -1 (-5775 3975)(-5775 3925);
WIRE 16 -1 (-5625 3925)(-5775 3925);
WIRE 16 -1 (-5775 3925)(-5775 3875);
WIRE 16 -1 (-5625 3875)(-5775 3875);
WIRE 16 -1 (-5775 3875)(-5775 3825);
WIRE 16 -1 (-5625 3825)(-5775 3825);
WIRE 16 -1 (-5775 3825)(-5775 3775);
WIRE 16 -1 (-5625 3775)(-5775 3775);
WIRE 16 -1 (-5775 3775)(-5775 3725);
WIRE 16 -1 (-5625 3725)(-5775 3725);
WIRE 16 -1 (-5775 3725)(-5775 3675);
WIRE 16 -1 (-5625 3675)(-5775 3675);
WIRE 16 -1 (-5775 3675)(-5775 3625);
WIRE 16 -1 (-5625 3625)(-5775 3625);
WIRE 16 -1 (-5775 3625)(-5775 3575);
WIRE 16 -1 (-5625 3575)(-5775 3575);
WIRE 16 -1 (-5775 3575)(-5775 3525);
WIRE 16 -1 (-5625 3525)(-5775 3525);
WIRE 16 -1 (-5775 3525)(-5775 3475);
WIRE 16 -1 (-5625 3475)(-5775 3475);
WIRE 16 -1 (-5775 3475)(-5775 3425);
WIRE 16 -1 (-5625 3425)(-5775 3425);
WIRE 16 -1 (-5775 3425)(-5775 3375);
WIRE 16 -1 (-5625 3375)(-5775 3375);
WIRE 16 -1 (-5775 3375)(-5775 3325);
WIRE 16 -1 (-5625 3325)(-5775 3325);
WIRE 16 -1 (-5775 3325)(-5775 3275);
WIRE 16 -1 (-5625 3275)(-5775 3275);
WIRE 16 -1 (-5775 3275)(-5775 3225);
WIRE 16 -1 (-5625 3225)(-5775 3225);
WIRE 16 -1 (-5775 3225)(-5775 3175);
WIRE 16 -1 (-5625 3175)(-5775 3175);
WIRE 16 -1 (-5775 3175)(-5775 3125);
WIRE 16 -1 (-5625 3125)(-5775 3125);
WIRE 16 -1 (-5775 3125)(-5775 3075);
WIRE 16 -1 (-5625 3075)(-5775 3075);
WIRE 16 -1 (-5775 3075)(-5775 3025);
WIRE 16 -1 (-5625 3025)(-5775 3025);
WIRE 16 -1 (-5775 3025)(-5775 2975);
WIRE 16 -1 (-5625 2975)(-5775 2975);
WIRE 16 -1 (-5775 2975)(-5775 2925);
WIRE 16 -1 (-5625 2925)(-5775 2925);
WIRE 16 -1 (-5775 2925)(-5775 2875);
WIRE 16 -1 (-5625 2875)(-5775 2875);
WIRE 16 -1 (-5775 2875)(-5775 2825);
WIRE 16 -1 (-5625 2825)(-5775 2825);
WIRE 16 -1 (-5775 2825)(-5775 2775);
WIRE 16 -1 (-5625 2775)(-5775 2775);
WIRE 16 -1 (-5775 2775)(-5775 2725);
WIRE 16 -1 (-5625 2725)(-5775 2725);
WIRE 16 -1 (-5775 2725)(-5775 2675);
WIRE 16 -1 (-5625 2675)(-5775 2675);
WIRE 16 -1 (-5775 2675)(-5775 2625);
WIRE 16 -1 (-5625 2625)(-5775 2625);
WIRE 16 -1 (-5775 2625)(-5775 2575);
WIRE 16 -1 (-5625 2575)(-5775 2575);
WIRE 16 -1 (-5775 2575)(-5775 2525);
WIRE 16 -1 (-5625 2525)(-5775 2525);
WIRE 16 -1 (-5775 2525)(-5775 2475);
WIRE 16 -1 (-5625 2475)(-5775 2475);
WIRE 16 -1 (-5775 2475)(-5775 2425);
WIRE 16 -1 (-5625 2425)(-5775 2425);
WIRE 16 -1 (-5775 2425)(-5775 2375);
WIRE 16 -1 (-5625 2375)(-5775 2375);
WIRE 16 -1 (-5775 2375)(-5775 2325);
WIRE 16 -1 (-5625 2325)(-5775 2325);
WIRE 16 -1 (-5775 2325)(-5775 2275);
WIRE 16 -1 (-5625 2275)(-5775 2275);
WIRE 16 -1 (-5775 2275)(-5775 2225);
WIRE 16 -1 (-5625 2225)(-5775 2225);
WIRE 16 -1 (-5775 2225)(-5775 2175);
WIRE 16 -1 (-5625 2175)(-5775 2175);
WIRE 16 -1 (-5775 2175)(-5775 2125);
WIRE 16 -1 (-5625 2125)(-5775 2125);
WIRE 16 -1 (-5775 2125)(-5775 2075);
WIRE 16 -1 (-5625 2075)(-5775 2075);
WIRE 16 -1 (-5775 2075)(-5775 2025);
WIRE 16 -1 (-5625 2025)(-5775 2025);
WIRE 16 -1 (-5775 2025)(-5775 1975);
WIRE 16 -1 (-5625 1975)(-5775 1975);
WIRE 16 -1 (-5775 1975)(-5775 1925);
WIRE 16 -1 (-5625 1925)(-5775 1925);
WIRE 16 -1 (-5775 1925)(-5775 1875);
WIRE 16 -1 (-5625 1875)(-5775 1875);
WIRE 16 -1 (-5775 1875)(-5775 1825);
WIRE 16 -1 (-5625 1825)(-5775 1825);
WIRE 16 -1 (-5775 1825)(-5775 1775);
WIRE 16 -1 (-5625 1775)(-5775 1775);
WIRE 16 -1 (-5775 1775)(-5775 1725);
WIRE 16 -1 (-5625 1725)(-5775 1725);
WIRE 16 -1 (-5775 1725)(-5775 1675);
WIRE 16 -1 (-5625 1675)(-5775 1675);
WIRE 16 -1 (-5775 1675)(-5775 1625);
WIRE 16 -1 (-5625 1625)(-5775 1625);
WIRE 16 -1 (-5775 1625)(-5775 1575);
WIRE 16 -1 (-5625 1575)(-5775 1575);
WIRE 16 -1 (-5775 1575)(-5775 1525);
WIRE 16 -1 (-5625 1525)(-5775 1525);
WIRE 16 -1 (-5775 1525)(-5775 1475);
WIRE 16 -1 (-5625 1475)(-5775 1475);
WIRE 16 -1 (-5775 1475)(-5775 1425);
WIRE 16 -1 (-5625 1425)(-5775 1425);
WIRE 16 -1 (-5775 1425)(-5775 1375);
WIRE 16 -1 (-5625 1375)(-5775 1375);
WIRE 16 -1 (-5775 1375)(-5775 1325);
WIRE 16 -1 (-5625 1325)(-5775 1325);
WIRE 16 -1 (-5775 1325)(-5775 1275);
WIRE 16 -1 (-5625 1275)(-5775 1275);
WIRE 16 -1 (-5775 1275)(-5775 1225);
WIRE 16 -1 (-5625 1225)(-5775 1225);
WIRE 16 -1 (-5775 1225)(-5775 1175);
WIRE 16 -1 (-5625 1175)(-5775 1175);
WIRE 16 -1 (-5775 1175)(-5775 1125);
WIRE 16 -1 (-5625 1125)(-5775 1125);
WIRE 16 -1 (-5775 1125)(-5775 1075);
WIRE 16 -1 (-5625 1075)(-5775 1075);
WIRE 16 -1 (-5775 1075)(-5775 1025);
WIRE 16 -1 (-5625 1025)(-5775 1025);
WIRE 16 -1 (-5775 1025)(-5775 975);
WIRE 16 -1 (-5625 975)(-5775 975);
WIRE 16 -1 (-5775 975)(-5775 925);
WIRE 16 -1 (-5625 925)(-5775 925);
WIRE 16 -1 (-5775 925)(-5775 875);
WIRE 16 -1 (-5625 875)(-5775 875);
WIRE 16 -1 (-5775 875)(-5775 825);
WIRE 16 -1 (-5625 825)(-5775 825);
WIRE 16 -1 (-5775 825)(-5775 775);
WIRE 16 -1 (-5625 775)(-5775 775);
WIRE 16 -1 (-5775 775)(-5775 725);
WIRE 16 -1 (-5625 725)(-5775 725);
WIRE 16 -1 (-5775 725)(-5775 675);
WIRE 16 -1 (-5775 675)(-5625 675);
WIRE 16 -1 (-5775 675)(-5775 550);
WIRE 16 -1 (-4250 4625)(-4425 4625);
WIRE 16 -1 (-4250 4625)(-4250 4575);
WIRE 16 -1 (-4425 4575)(-4250 4575);
WIRE 16 -1 (-4250 4575)(-4250 4525);
WIRE 16 -1 (-4425 4525)(-4250 4525);
WIRE 16 -1 (-4250 4525)(-4250 4475);
WIRE 16 -1 (-4425 4475)(-4250 4475);
WIRE 16 -1 (-4250 4475)(-4250 4425);
WIRE 16 -1 (-4425 4425)(-4250 4425);
WIRE 16 -1 (-4250 4425)(-4250 4375);
WIRE 16 -1 (-4425 4375)(-4250 4375);
WIRE 16 -1 (-4250 4375)(-4250 4325);
WIRE 16 -1 (-4425 4325)(-4250 4325);
WIRE 16 -1 (-4250 4325)(-4250 4275);
WIRE 16 -1 (-4425 4275)(-4250 4275);
WIRE 16 -1 (-4250 4275)(-4250 4225);
WIRE 16 -1 (-4425 4225)(-4250 4225);
WIRE 16 -1 (-4250 4225)(-4250 4175);
WIRE 16 -1 (-4425 4175)(-4250 4175);
WIRE 16 -1 (-4250 4175)(-4250 4125);
WIRE 16 -1 (-4425 4125)(-4250 4125);
WIRE 16 -1 (-4250 4125)(-4250 4075);
WIRE 16 -1 (-4425 4075)(-4250 4075);
WIRE 16 -1 (-4250 4075)(-4250 4025);
WIRE 16 -1 (-4425 4025)(-4250 4025);
WIRE 16 -1 (-4250 4025)(-4250 3975);
WIRE 16 -1 (-4425 3975)(-4250 3975);
WIRE 16 -1 (-4250 3975)(-4250 3925);
WIRE 16 -1 (-4425 3925)(-4250 3925);
WIRE 16 -1 (-4250 3925)(-4250 3875);
WIRE 16 -1 (-4425 3875)(-4250 3875);
WIRE 16 -1 (-4250 3875)(-4250 3825);
WIRE 16 -1 (-4425 3825)(-4250 3825);
WIRE 16 -1 (-4250 3825)(-4250 3775);
WIRE 16 -1 (-4425 3775)(-4250 3775);
WIRE 16 -1 (-4250 3775)(-4250 3725);
WIRE 16 -1 (-4425 3725)(-4250 3725);
WIRE 16 -1 (-4250 3725)(-4250 3675);
WIRE 16 -1 (-4425 3675)(-4250 3675);
WIRE 16 -1 (-4250 3675)(-4250 3625);
WIRE 16 -1 (-4425 3625)(-4250 3625);
WIRE 16 -1 (-4250 3625)(-4250 3575);
WIRE 16 -1 (-4425 3575)(-4250 3575);
WIRE 16 -1 (-4250 3575)(-4250 3525);
WIRE 16 -1 (-4425 3525)(-4250 3525);
WIRE 16 -1 (-4250 3525)(-4250 3475);
WIRE 16 -1 (-4425 3475)(-4250 3475);
WIRE 16 -1 (-4250 3475)(-4250 3425);
WIRE 16 -1 (-4425 3425)(-4250 3425);
WIRE 16 -1 (-4250 3425)(-4250 3375);
WIRE 16 -1 (-4425 3375)(-4250 3375);
WIRE 16 -1 (-4250 3375)(-4250 3325);
WIRE 16 -1 (-4425 3325)(-4250 3325);
WIRE 16 -1 (-4250 3325)(-4250 3275);
WIRE 16 -1 (-4425 3275)(-4250 3275);
WIRE 16 -1 (-4250 3275)(-4250 3225);
WIRE 16 -1 (-4425 3225)(-4250 3225);
WIRE 16 -1 (-4250 3225)(-4250 3175);
WIRE 16 -1 (-4425 3175)(-4250 3175);
WIRE 16 -1 (-4250 3175)(-4250 3125);
WIRE 16 -1 (-4425 3125)(-4250 3125);
WIRE 16 -1 (-4250 3125)(-4250 3075);
WIRE 16 -1 (-4425 3075)(-4250 3075);
WIRE 16 -1 (-4250 3075)(-4250 3025);
WIRE 16 -1 (-4425 3025)(-4250 3025);
WIRE 16 -1 (-4250 3025)(-4250 2975);
WIRE 16 -1 (-4425 2975)(-4250 2975);
WIRE 16 -1 (-4250 2975)(-4250 2925);
WIRE 16 -1 (-4425 2925)(-4250 2925);
WIRE 16 -1 (-4250 2925)(-4250 2875);
WIRE 16 -1 (-4425 2875)(-4250 2875);
WIRE 16 -1 (-4250 2875)(-4250 2825);
WIRE 16 -1 (-4425 2825)(-4250 2825);
WIRE 16 -1 (-4250 2825)(-4250 2775);
WIRE 16 -1 (-4425 2775)(-4250 2775);
WIRE 16 -1 (-4250 2775)(-4250 2725);
WIRE 16 -1 (-4425 2725)(-4250 2725);
WIRE 16 -1 (-4250 2725)(-4250 2675);
WIRE 16 -1 (-4425 2675)(-4250 2675);
WIRE 16 -1 (-4250 2675)(-4250 2625);
WIRE 16 -1 (-4425 2625)(-4250 2625);
WIRE 16 -1 (-4250 2625)(-4250 2575);
WIRE 16 -1 (-4425 2575)(-4250 2575);
WIRE 16 -1 (-4250 2575)(-4250 2525);
WIRE 16 -1 (-4425 2525)(-4250 2525);
WIRE 16 -1 (-4250 2525)(-4250 2475);
WIRE 16 -1 (-4425 2475)(-4250 2475);
WIRE 16 -1 (-4250 2475)(-4250 2425);
WIRE 16 -1 (-4425 2425)(-4250 2425);
WIRE 16 -1 (-4250 2425)(-4250 2375);
WIRE 16 -1 (-4425 2375)(-4250 2375);
WIRE 16 -1 (-4250 2375)(-4250 2325);
WIRE 16 -1 (-4425 2325)(-4250 2325);
WIRE 16 -1 (-4250 2325)(-4250 2275);
WIRE 16 -1 (-4425 2275)(-4250 2275);
WIRE 16 -1 (-4250 2275)(-4250 2225);
WIRE 16 -1 (-4425 2225)(-4250 2225);
WIRE 16 -1 (-4250 2225)(-4250 2175);
WIRE 16 -1 (-4425 2175)(-4250 2175);
WIRE 16 -1 (-4250 2175)(-4250 2125);
WIRE 16 -1 (-4425 2125)(-4250 2125);
WIRE 16 -1 (-4250 2125)(-4250 2075);
WIRE 16 -1 (-4425 2075)(-4250 2075);
WIRE 16 -1 (-4250 2075)(-4250 2025);
WIRE 16 -1 (-4425 2025)(-4250 2025);
WIRE 16 -1 (-4250 2025)(-4250 1975);
WIRE 16 -1 (-4425 1975)(-4250 1975);
WIRE 16 -1 (-4250 1975)(-4250 1925);
WIRE 16 -1 (-4425 1925)(-4250 1925);
WIRE 16 -1 (-4250 1925)(-4250 1875);
WIRE 16 -1 (-4425 1875)(-4250 1875);
WIRE 16 -1 (-4250 1875)(-4250 1825);
WIRE 16 -1 (-4425 1825)(-4250 1825);
WIRE 16 -1 (-4250 1825)(-4250 1775);
WIRE 16 -1 (-4425 1775)(-4250 1775);
WIRE 16 -1 (-4250 1775)(-4250 1725);
WIRE 16 -1 (-4425 1725)(-4250 1725);
WIRE 16 -1 (-4250 1725)(-4250 1675);
WIRE 16 -1 (-4425 1675)(-4250 1675);
WIRE 16 -1 (-4250 1675)(-4250 1625);
WIRE 16 -1 (-4425 1625)(-4250 1625);
WIRE 16 -1 (-4250 1625)(-4250 1575);
WIRE 16 -1 (-4425 1575)(-4250 1575);
WIRE 16 -1 (-4250 1575)(-4250 1525);
WIRE 16 -1 (-4425 1525)(-4250 1525);
WIRE 16 -1 (-4250 1525)(-4250 1475);
WIRE 16 -1 (-4425 1475)(-4250 1475);
WIRE 16 -1 (-4250 1475)(-4250 1425);
WIRE 16 -1 (-4425 1425)(-4250 1425);
WIRE 16 -1 (-4250 1425)(-4250 1375);
WIRE 16 -1 (-4425 1375)(-4250 1375);
WIRE 16 -1 (-4250 1375)(-4250 1325);
WIRE 16 -1 (-4425 1325)(-4250 1325);
WIRE 16 -1 (-4250 1325)(-4250 1275);
WIRE 16 -1 (-4425 1275)(-4250 1275);
WIRE 16 -1 (-4250 1275)(-4250 1225);
WIRE 16 -1 (-4425 1225)(-4250 1225);
WIRE 16 -1 (-4250 1225)(-4250 1175);
WIRE 16 -1 (-4425 1175)(-4250 1175);
WIRE 16 -1 (-4250 1175)(-4250 1125);
WIRE 16 -1 (-4425 1125)(-4250 1125);
WIRE 16 -1 (-4250 1125)(-4250 1075);
WIRE 16 -1 (-4425 1075)(-4250 1075);
WIRE 16 -1 (-4250 1075)(-4250 1025);
WIRE 16 -1 (-4425 1025)(-4250 1025);
WIRE 16 -1 (-4250 1025)(-4250 975);
WIRE 16 -1 (-4425 975)(-4250 975);
WIRE 16 -1 (-4250 975)(-4250 925);
WIRE 16 -1 (-4425 925)(-4250 925);
WIRE 16 -1 (-4250 925)(-4250 875);
WIRE 16 -1 (-4425 875)(-4250 875);
WIRE 16 -1 (-4250 875)(-4250 825);
WIRE 16 -1 (-4425 825)(-4250 825);
WIRE 16 -1 (-4250 825)(-4250 775);
WIRE 16 -1 (-4425 775)(-4250 775);
WIRE 16 -1 (-4250 775)(-4250 725);
WIRE 16 -1 (-4425 725)(-4250 725);
WIRE 16 -1 (-4250 725)(-4250 675);
WIRE 16 -1 (-4425 675)(-4250 675);
WIRE 16 -1 (-4250 675)(-4250 550);
WIRE 16 -1 (-3950 4625)(-3800 4625);
WIRE 16 -1 (-3950 4625)(-3950 4575);
WIRE 16 -1 (-3800 4575)(-3950 4575);
WIRE 16 -1 (-3950 4575)(-3950 4525);
WIRE 16 -1 (-3800 4525)(-3950 4525);
WIRE 16 -1 (-3950 4525)(-3950 4475);
WIRE 16 -1 (-3800 4475)(-3950 4475);
WIRE 16 -1 (-3950 4475)(-3950 4425);
WIRE 16 -1 (-3800 4425)(-3950 4425);
WIRE 16 -1 (-3950 4425)(-3950 4375);
WIRE 16 -1 (-3800 4375)(-3950 4375);
WIRE 16 -1 (-3950 4375)(-3950 4325);
WIRE 16 -1 (-3800 4325)(-3950 4325);
WIRE 16 -1 (-3950 4325)(-3950 4275);
WIRE 16 -1 (-3800 4275)(-3950 4275);
WIRE 16 -1 (-3950 4275)(-3950 4225);
WIRE 16 -1 (-3800 4225)(-3950 4225);
WIRE 16 -1 (-3950 4225)(-3950 4175);
WIRE 16 -1 (-3800 4175)(-3950 4175);
WIRE 16 -1 (-3950 4175)(-3950 4125);
WIRE 16 -1 (-3800 4125)(-3950 4125);
WIRE 16 -1 (-3950 4125)(-3950 4075);
WIRE 16 -1 (-3800 4075)(-3950 4075);
WIRE 16 -1 (-3950 4075)(-3950 4025);
WIRE 16 -1 (-3800 4025)(-3950 4025);
WIRE 16 -1 (-3950 4025)(-3950 3975);
WIRE 16 -1 (-3800 3975)(-3950 3975);
WIRE 16 -1 (-3950 3975)(-3950 3925);
WIRE 16 -1 (-3800 3925)(-3950 3925);
WIRE 16 -1 (-3950 3925)(-3950 3875);
WIRE 16 -1 (-3800 3875)(-3950 3875);
WIRE 16 -1 (-3950 3875)(-3950 3825);
WIRE 16 -1 (-3800 3825)(-3950 3825);
WIRE 16 -1 (-3950 3825)(-3950 3775);
WIRE 16 -1 (-3800 3775)(-3950 3775);
WIRE 16 -1 (-3950 3775)(-3950 3725);
WIRE 16 -1 (-3800 3725)(-3950 3725);
WIRE 16 -1 (-3950 3725)(-3950 3675);
WIRE 16 -1 (-3800 3675)(-3950 3675);
WIRE 16 -1 (-3950 3675)(-3950 3625);
WIRE 16 -1 (-3800 3625)(-3950 3625);
WIRE 16 -1 (-3950 3625)(-3950 3575);
WIRE 16 -1 (-3800 3575)(-3950 3575);
WIRE 16 -1 (-3950 3575)(-3950 3525);
WIRE 16 -1 (-3800 3525)(-3950 3525);
WIRE 16 -1 (-3950 3525)(-3950 3475);
WIRE 16 -1 (-3800 3475)(-3950 3475);
WIRE 16 -1 (-3950 3475)(-3950 3425);
WIRE 16 -1 (-3800 3425)(-3950 3425);
WIRE 16 -1 (-3950 3425)(-3950 3375);
WIRE 16 -1 (-3800 3375)(-3950 3375);
WIRE 16 -1 (-3950 3375)(-3950 3325);
WIRE 16 -1 (-3800 3325)(-3950 3325);
WIRE 16 -1 (-3950 3325)(-3950 3275);
WIRE 16 -1 (-3800 3275)(-3950 3275);
WIRE 16 -1 (-3950 3275)(-3950 3225);
WIRE 16 -1 (-3800 3225)(-3950 3225);
WIRE 16 -1 (-3950 3225)(-3950 3175);
WIRE 16 -1 (-3800 3175)(-3950 3175);
WIRE 16 -1 (-3950 3175)(-3950 3125);
WIRE 16 -1 (-3800 3125)(-3950 3125);
WIRE 16 -1 (-3950 3125)(-3950 3075);
WIRE 16 -1 (-3800 3075)(-3950 3075);
WIRE 16 -1 (-3950 3075)(-3950 3025);
WIRE 16 -1 (-3800 3025)(-3950 3025);
WIRE 16 -1 (-3950 3025)(-3950 2975);
WIRE 16 -1 (-3800 2975)(-3950 2975);
WIRE 16 -1 (-3950 2975)(-3950 2925);
WIRE 16 -1 (-3800 2925)(-3950 2925);
WIRE 16 -1 (-3950 2925)(-3950 2875);
WIRE 16 -1 (-3800 2875)(-3950 2875);
WIRE 16 -1 (-3950 2875)(-3950 2825);
WIRE 16 -1 (-3800 2825)(-3950 2825);
WIRE 16 -1 (-3950 2825)(-3950 2775);
WIRE 16 -1 (-3800 2775)(-3950 2775);
WIRE 16 -1 (-3950 2775)(-3950 2725);
WIRE 16 -1 (-3800 2725)(-3950 2725);
WIRE 16 -1 (-3950 2725)(-3950 2675);
WIRE 16 -1 (-3800 2675)(-3950 2675);
WIRE 16 -1 (-3950 2675)(-3950 2625);
WIRE 16 -1 (-3800 2625)(-3950 2625);
WIRE 16 -1 (-3950 2625)(-3950 2575);
WIRE 16 -1 (-3800 2575)(-3950 2575);
WIRE 16 -1 (-3950 2575)(-3950 2525);
WIRE 16 -1 (-3800 2525)(-3950 2525);
WIRE 16 -1 (-3950 2525)(-3950 2475);
WIRE 16 -1 (-3800 2475)(-3950 2475);
WIRE 16 -1 (-3950 2475)(-3950 2425);
WIRE 16 -1 (-3800 2425)(-3950 2425);
WIRE 16 -1 (-3950 2425)(-3950 2375);
WIRE 16 -1 (-3800 2375)(-3950 2375);
WIRE 16 -1 (-3950 2375)(-3950 2325);
WIRE 16 -1 (-3800 2325)(-3950 2325);
WIRE 16 -1 (-3950 2325)(-3950 2275);
WIRE 16 -1 (-3800 2275)(-3950 2275);
WIRE 16 -1 (-3950 2275)(-3950 2225);
WIRE 16 -1 (-3800 2225)(-3950 2225);
WIRE 16 -1 (-3950 2225)(-3950 2175);
WIRE 16 -1 (-3800 2175)(-3950 2175);
WIRE 16 -1 (-3950 2175)(-3950 2125);
WIRE 16 -1 (-3800 2125)(-3950 2125);
WIRE 16 -1 (-3950 2125)(-3950 2075);
WIRE 16 -1 (-3800 2075)(-3950 2075);
WIRE 16 -1 (-3950 2075)(-3950 2025);
WIRE 16 -1 (-3800 2025)(-3950 2025);
WIRE 16 -1 (-3950 2025)(-3950 1975);
WIRE 16 -1 (-3800 1975)(-3950 1975);
WIRE 16 -1 (-3950 1975)(-3950 1925);
WIRE 16 -1 (-3800 1925)(-3950 1925);
WIRE 16 -1 (-3950 1925)(-3950 1875);
WIRE 16 -1 (-3800 1875)(-3950 1875);
WIRE 16 -1 (-3950 1875)(-3950 1825);
WIRE 16 -1 (-3800 1825)(-3950 1825);
WIRE 16 -1 (-3950 1825)(-3950 1775);
WIRE 16 -1 (-3800 1775)(-3950 1775);
WIRE 16 -1 (-3950 1775)(-3950 1725);
WIRE 16 -1 (-3800 1725)(-3950 1725);
WIRE 16 -1 (-3950 1725)(-3950 1675);
WIRE 16 -1 (-3800 1675)(-3950 1675);
WIRE 16 -1 (-3950 1675)(-3950 1625);
WIRE 16 -1 (-3800 1625)(-3950 1625);
WIRE 16 -1 (-3950 1625)(-3950 1575);
WIRE 16 -1 (-3800 1575)(-3950 1575);
WIRE 16 -1 (-3950 1575)(-3950 1525);
WIRE 16 -1 (-3800 1525)(-3950 1525);
WIRE 16 -1 (-3950 1525)(-3950 1475);
WIRE 16 -1 (-3800 1475)(-3950 1475);
WIRE 16 -1 (-3950 1475)(-3950 1425);
WIRE 16 -1 (-3800 1425)(-3950 1425);
WIRE 16 -1 (-3950 1425)(-3950 1375);
WIRE 16 -1 (-3800 1375)(-3950 1375);
WIRE 16 -1 (-3950 1375)(-3950 1325);
WIRE 16 -1 (-3800 1325)(-3950 1325);
WIRE 16 -1 (-3950 1325)(-3950 1275);
WIRE 16 -1 (-3800 1275)(-3950 1275);
WIRE 16 -1 (-3950 1275)(-3950 1225);
WIRE 16 -1 (-3800 1225)(-3950 1225);
WIRE 16 -1 (-3950 1225)(-3950 1175);
WIRE 16 -1 (-3800 1175)(-3950 1175);
WIRE 16 -1 (-3950 1175)(-3950 1125);
WIRE 16 -1 (-3800 1125)(-3950 1125);
WIRE 16 -1 (-3950 1125)(-3950 1075);
WIRE 16 -1 (-3800 1075)(-3950 1075);
WIRE 16 -1 (-3950 1075)(-3950 1025);
WIRE 16 -1 (-3800 1025)(-3950 1025);
WIRE 16 -1 (-3950 1025)(-3950 975);
WIRE 16 -1 (-3800 975)(-3950 975);
WIRE 16 -1 (-3950 975)(-3950 925);
WIRE 16 -1 (-3800 925)(-3950 925);
WIRE 16 -1 (-3950 925)(-3950 875);
WIRE 16 -1 (-3800 875)(-3950 875);
WIRE 16 -1 (-3950 875)(-3950 825);
WIRE 16 -1 (-3800 825)(-3950 825);
WIRE 16 -1 (-3950 825)(-3950 775);
WIRE 16 -1 (-3800 775)(-3950 775);
WIRE 16 -1 (-3950 775)(-3950 725);
WIRE 16 -1 (-3800 725)(-3950 725);
WIRE 16 -1 (-3950 725)(-3950 675);
WIRE 16 -1 (-3950 675)(-3800 675);
WIRE 16 -1 (-3950 675)(-3950 550);
DOT 1 (-3950 975);
DOT 1 (-3950 1925);
DOT 1 (-4250 3775);
DOT 1 (-4250 1425);
DOT 1 (-4250 1725);
DOT 1 (-5775 3725);
DOT 1 (-5775 3775);
DOT 1 (-5775 3825);
DOT 1 (-5775 2125);
DOT 1 (-6100 4450);
DOT 1 (-6100 4500);
DOT 1 (-6100 3150);
DOT 1 (-5775 4325);
DOT 1 (-6100 3700);
DOT 1 (-6100 3650);
DOT 1 (-6100 3600);
DOT 1 (-5775 2075);
DOT 1 (-6100 4550);
DOT 1 (-6100 4400);
DOT 1 (-6100 4350);
DOT 1 (-6100 4300);
DOT 1 (-6100 4250);
DOT 1 (-6100 4200);
DOT 1 (-6100 4150);
DOT 1 (-7625 4550);
DOT 1 (-7625 4500);
DOT 1 (-7625 4450);
DOT 1 (-7625 4400);
DOT 1 (-7625 4350);
DOT 1 (-7625 4300);
DOT 1 (-7625 4250);
DOT 1 (-7625 4200);
DOT 1 (-7625 4150);
DOT 1 (-7625 4100);
DOT 1 (-6100 4100);
DOT 1 (-6100 4050);
DOT 1 (-6100 4000);
DOT 1 (-6100 3950);
DOT 1 (-6100 3900);
DOT 1 (-6100 3850);
DOT 1 (-6100 3800);
DOT 1 (-6100 3750);
DOT 1 (-6100 3450);
DOT 1 (-6100 3400);
DOT 1 (-6100 3350);
DOT 1 (-6100 3250);
DOT 1 (-6100 3200);
DOT 1 (-6100 3100);
DOT 1 (-6100 3050);
DOT 1 (-6100 3000);
DOT 1 (-6100 2950);
DOT 1 (-6100 2900);
DOT 1 (-6100 2850);
DOT 1 (-6100 2800);
DOT 1 (-6100 2750);
DOT 1 (-6100 2700);
DOT 1 (-6100 2650);
DOT 1 (-6100 2600);
DOT 1 (-6100 2550);
DOT 1 (-6100 2500);
DOT 1 (-6100 2450);
DOT 1 (-6100 2400);
DOT 1 (-6100 2350);
DOT 1 (-6100 2200);
DOT 1 (-6100 2150);
DOT 1 (-6100 2100);
DOT 1 (-6100 2050);
DOT 1 (-6100 2000);
DOT 1 (-6100 1950);
DOT 1 (-6100 1900);
DOT 1 (-6100 1850);
DOT 1 (-6100 1800);
DOT 1 (-6100 1750);
DOT 1 (-6100 1700);
DOT 1 (-6100 1650);
DOT 1 (-6100 1450);
DOT 1 (-6100 1400);
DOT 1 (-6100 1350);
DOT 1 (-6100 1250);
DOT 1 (-6100 1200);
DOT 1 (-6100 1050);
DOT 1 (-6100 1000);
DOT 1 (-6100 950);
DOT 1 (-6100 900);
DOT 1 (-6100 850);
DOT 1 (-6100 800);
DOT 1 (-6100 750);
DOT 1 (-6100 700);
DOT 1 (-6100 650);
DOT 1 (-7625 4050);
DOT 1 (-7625 4000);
DOT 1 (-7625 3950);
DOT 1 (-7625 3900);
DOT 1 (-7625 3850);
DOT 1 (-7625 3800);
DOT 1 (-7625 3750);
DOT 1 (-7625 3700);
DOT 1 (-7625 3650);
DOT 1 (-7625 3600);
DOT 1 (-7625 3550);
DOT 1 (-7625 3500);
DOT 1 (-7625 3450);
DOT 1 (-7625 3400);
DOT 1 (-7625 3350);
DOT 1 (-7625 3300);
DOT 1 (-7625 3250);
DOT 1 (-7625 3200);
DOT 1 (-7625 3100);
DOT 1 (-7625 3150);
DOT 1 (-7625 3050);
DOT 1 (-7625 3000);
DOT 1 (-7625 2950);
DOT 1 (-7625 2900);
DOT 1 (-7625 2850);
DOT 1 (-7625 2800);
DOT 1 (-7625 2750);
DOT 1 (-7625 2700);
DOT 1 (-7625 2650);
DOT 1 (-7625 2550);
DOT 1 (-7625 2500);
DOT 1 (-7625 2450);
DOT 1 (-7625 2400);
DOT 1 (-7625 2350);
DOT 1 (-7625 2300);
DOT 1 (-7625 2250);
DOT 1 (-7625 2200);
DOT 1 (-7625 2150);
DOT 1 (-7625 2100);
DOT 1 (-7625 2050);
DOT 1 (-7625 2000);
DOT 1 (-7625 1950);
DOT 1 (-7625 1900);
DOT 1 (-7625 1850);
DOT 1 (-7625 1800);
DOT 1 (-7625 1750);
DOT 1 (-7625 1700);
DOT 1 (-7625 1650);
DOT 1 (-7625 1600);
DOT 1 (-7625 1550);
DOT 1 (-7625 1500);
DOT 1 (-7625 1450);
DOT 1 (-7625 1400);
DOT 1 (-7625 1350);
DOT 1 (-7625 1250);
DOT 1 (-7625 1200);
DOT 1 (-7625 1150);
DOT 1 (-7625 1100);
DOT 1 (-7625 1050);
DOT 1 (-7625 1000);
DOT 1 (-7625 950);
DOT 1 (-7625 850);
DOT 1 (-7625 800);
DOT 1 (-7625 750);
DOT 1 (-7625 700);
DOT 1 (-7625 650);
DOT 1 (-4250 4575);
DOT 1 (-4250 4525);
DOT 1 (-4250 4425);
DOT 1 (-4250 4375);
DOT 1 (-4250 4325);
DOT 1 (-4250 4275);
DOT 1 (-4250 4225);
DOT 1 (-4250 4125);
DOT 1 (-4250 4175);
DOT 1 (-5775 4275);
DOT 1 (-5775 4225);
DOT 1 (-5775 4125);
DOT 1 (-5775 4175);
DOT 1 (-4250 4075);
DOT 1 (-4250 4025);
DOT 1 (-4250 3975);
DOT 1 (-4250 3875);
DOT 1 (-4250 3925);
DOT 1 (-4250 3825);
DOT 1 (-4250 3725);
DOT 1 (-4250 3625);
DOT 1 (-4250 3675);
DOT 1 (-4250 3575);
DOT 1 (-4250 3525);
DOT 1 (-4250 3475);
DOT 1 (-4250 3425);
DOT 1 (-4250 3375);
DOT 1 (-4250 3325);
DOT 1 (-4250 3275);
DOT 1 (-4250 3225);
DOT 1 (-4250 3175);
DOT 1 (-4250 3125);
DOT 1 (-4250 3075);
DOT 1 (-4250 3025);
DOT 1 (-4250 2975);
DOT 1 (-4250 2925);
DOT 1 (-4250 2875);
DOT 1 (-4250 2825);
DOT 1 (-4250 2775);
DOT 1 (-4250 2725);
DOT 1 (-4250 2675);
DOT 1 (-4250 2625);
DOT 1 (-4250 2575);
DOT 1 (-4250 2475);
DOT 1 (-4250 2425);
DOT 1 (-4250 2375);
DOT 1 (-4250 2325);
DOT 1 (-4250 2275);
DOT 1 (-4250 2225);
DOT 1 (-4250 2175);
DOT 1 (-4250 2125);
DOT 1 (-4250 2075);
DOT 1 (-4250 2025);
DOT 1 (-4250 1975);
DOT 1 (-4250 1925);
DOT 1 (-4250 1875);
DOT 1 (-4250 1825);
DOT 1 (-4250 1775);
DOT 1 (-4250 1675);
DOT 1 (-4250 1575);
DOT 1 (-4250 1625);
DOT 1 (-4250 1525);
DOT 1 (-4250 1475);
DOT 1 (-4250 1375);
DOT 1 (-4250 1325);
DOT 1 (-4250 1275);
DOT 1 (-4250 1225);
DOT 1 (-4250 1175);
DOT 1 (-4250 1125);
DOT 1 (-4250 1075);
DOT 1 (-4250 1025);
DOT 1 (-4250 975);
DOT 1 (-4250 925);
DOT 1 (-4250 875);
DOT 1 (-4250 825);
DOT 1 (-4250 775);
DOT 1 (-4250 725);
DOT 1 (-4250 675);
DOT 1 (-5775 4075);
DOT 1 (-5775 4025);
DOT 1 (-5775 3975);
DOT 1 (-5775 3875);
DOT 1 (-5775 3925);
DOT 1 (-5775 3625);
DOT 1 (-5775 3675);
DOT 1 (-5775 3575);
DOT 1 (-5775 3525);
DOT 1 (-5775 3475);
DOT 1 (-5775 3375);
DOT 1 (-5775 3325);
DOT 1 (-5775 3275);
DOT 1 (-5775 3225);
DOT 1 (-5775 3175);
DOT 1 (-5775 3125);
DOT 1 (-5775 3075);
DOT 1 (-5775 2975);
DOT 1 (-5775 3025);
DOT 1 (-5775 2925);
DOT 1 (-5775 2825);
DOT 1 (-5775 2775);
DOT 1 (-5775 2725);
DOT 1 (-5775 2675);
DOT 1 (-5775 2625);
DOT 1 (-5775 2575);
DOT 1 (-5775 2525);
DOT 1 (-5775 2475);
DOT 1 (-5775 2375);
DOT 1 (-5775 2325);
DOT 1 (-5775 2275);
DOT 1 (-5775 2225);
DOT 1 (-5775 2175);
DOT 1 (-5775 2025);
DOT 1 (-5775 1975);
DOT 1 (-5775 1925);
DOT 1 (-5775 1825);
DOT 1 (-5775 1875);
DOT 1 (-5775 1775);
DOT 1 (-5775 1725);
DOT 1 (-5775 1675);
DOT 1 (-5775 1575);
DOT 1 (-5775 1625);
DOT 1 (-5775 1525);
DOT 1 (-5775 1475);
DOT 1 (-5775 1425);
DOT 1 (-5775 1325);
DOT 1 (-5775 1375);
DOT 1 (-5775 1275);
DOT 1 (-5775 1225);
DOT 1 (-5775 1125);
DOT 1 (-5775 1075);
DOT 1 (-5775 1025);
DOT 1 (-5775 975);
DOT 1 (-5775 925);
DOT 1 (-5775 875);
DOT 1 (-5775 825);
DOT 1 (-5775 775);
DOT 1 (-5775 675);
DOT 1 (-5775 725);
DOT 1 (-3950 675);
DOT 1 (-3950 775);
DOT 1 (-3950 725);
DOT 1 (-3950 875);
DOT 1 (-3950 825);
DOT 1 (-3950 925);
DOT 1 (-3950 1025);
DOT 1 (-3950 1175);
DOT 1 (-3950 1125);
DOT 1 (-3950 1075);
DOT 1 (-3950 1275);
DOT 1 (-3950 1225);
DOT 1 (-3950 1425);
DOT 1 (-3950 1375);
DOT 1 (-3950 1325);
DOT 1 (-3950 1525);
DOT 1 (-3950 1475);
DOT 1 (-3950 1625);
DOT 1 (-3950 1675);
DOT 1 (-3950 1575);
DOT 1 (-3950 1775);
DOT 1 (-3950 1725);
DOT 1 (-3950 1825);
DOT 1 (-3950 1875);
DOT 1 (-3950 2025);
DOT 1 (-3950 1975);
DOT 1 (-3950 2075);
DOT 1 (-3950 2175);
DOT 1 (-3950 2125);
DOT 1 (-3950 2325);
DOT 1 (-3950 2275);
DOT 1 (-3950 2225);
DOT 1 (-3950 2425);
DOT 1 (-3950 2375);
DOT 1 (-3950 2575);
DOT 1 (-3950 2525);
DOT 1 (-3950 2475);
DOT 1 (-3950 2675);
DOT 1 (-3950 2625);
DOT 1 (-3950 2725);
DOT 1 (-3950 2825);
DOT 1 (-3950 2775);
DOT 1 (-3950 2925);
DOT 1 (-3950 2875);
DOT 1 (-3950 2975);
DOT 1 (-3950 3075);
DOT 1 (-3950 3025);
DOT 1 (-3950 3175);
DOT 1 (-3950 3225);
DOT 1 (-3950 3125);
DOT 1 (-3950 3275);
DOT 1 (-3950 3475);
DOT 1 (-3950 3425);
DOT 1 (-3950 3375);
DOT 1 (-3950 3525);
DOT 1 (-3950 3725);
DOT 1 (-3950 3675);
DOT 1 (-3950 3625);
DOT 1 (-3950 3825);
DOT 1 (-3950 3775);
DOT 1 (-3950 3875);
DOT 1 (-3950 3975);
DOT 1 (-3950 3925);
DOT 1 (-3950 4075);
DOT 1 (-3950 4025);
DOT 1 (-2425 675);
DOT 1 (-2425 775);
DOT 1 (-2425 725);
DOT 1 (-2425 825);
DOT 1 (-2425 875);
DOT 1 (-2425 925);
DOT 1 (-2425 1025);
DOT 1 (-2425 975);
DOT 1 (-2425 1175);
DOT 1 (-2425 1125);
DOT 1 (-2425 1075);
DOT 1 (-2425 1225);
DOT 1 (-2425 1275);
DOT 1 (-2425 1375);
DOT 1 (-2425 1425);
DOT 1 (-2425 1325);
DOT 1 (-2425 1525);
DOT 1 (-2425 1475);
DOT 1 (-2425 1575);
DOT 1 (-2425 1625);
DOT 1 (-2425 1675);
DOT 1 (-2425 1725);
DOT 1 (-2425 1775);
DOT 1 (-2425 1825);
DOT 1 (-2425 1925);
DOT 1 (-2425 1875);
DOT 1 (-2425 1975);
DOT 1 (-2425 2025);
DOT 1 (-2425 2075);
DOT 1 (-2425 2175);
DOT 1 (-2425 2125);
DOT 1 (-2425 2325);
DOT 1 (-2425 2275);
DOT 1 (-2425 2225);
DOT 1 (-2425 2375);
DOT 1 (-2425 2425);
DOT 1 (-2425 2575);
DOT 1 (-2425 2525);
DOT 1 (-2425 2475);
DOT 1 (-2425 2625);
DOT 1 (-2425 2675);
DOT 1 (-2425 2725);
DOT 1 (-2425 2825);
DOT 1 (-2425 2775);
DOT 1 (-2425 2875);
DOT 1 (-2425 2925);
DOT 1 (-2425 2975);
DOT 1 (-2425 3075);
DOT 1 (-2425 3025);
DOT 1 (-2425 3125);
DOT 1 (-2425 3175);
DOT 1 (-2425 3225);
DOT 1 (-2425 3275);
DOT 1 (-2425 3325);
DOT 1 (-2425 3425);
DOT 1 (-2425 3475);
DOT 1 (-2425 3375);
DOT 1 (-2425 3525);
DOT 1 (-2425 3575);
DOT 1 (-2425 3725);
DOT 1 (-2425 3625);
DOT 1 (-2425 3775);
DOT 1 (-2425 3975);
DOT 1 (-2425 3925);
DOT 1 (-2425 4025);
DOT 1 (-2425 4075);
DOT 1 (-2425 4125);
DOT 1 (-3950 4125);
DOT 1 (-3950 4225);
DOT 1 (-3950 4175);
DOT 1 (-3950 4375);
DOT 1 (-3950 4325);
DOT 1 (-3950 4275);
DOT 1 (-3950 4475);
DOT 1 (-3950 4425);
DOT 1 (-3950 4575);
DOT 1 (-2425 4225);
DOT 1 (-2425 4175);
DOT 1 (-2425 4375);
DOT 1 (-2425 4325);
DOT 1 (-2425 4275);
DOT 1 (-2425 4475);
DOT 1 (-2425 4425);
DOT 1 (-2425 4525);
DOT 1 (-2425 4575);
DOT 1 (-2025 650);
DOT 1 (-2025 700);
DOT 1 (-2025 800);
DOT 1 (-2025 750);
DOT 1 (-2025 850);
DOT 1 (-2025 900);
DOT 1 (-2025 950);
DOT 1 (-2025 1050);
DOT 1 (-2025 1000);
DOT 1 (-2025 1200);
DOT 1 (-2025 1150);
DOT 1 (-2025 1100);
DOT 1 (-2025 1250);
DOT 1 (-2025 1300);
DOT 1 (-2025 1450);
DOT 1 (-2025 1350);
DOT 1 (-2025 1400);
DOT 1 (-2025 1500);
DOT 1 (-2025 1550);
DOT 1 (-2025 1600);
DOT 1 (-2025 1650);
DOT 1 (-2025 1700);
DOT 1 (-2025 1750);
DOT 1 (-2025 1800);
DOT 1 (-2025 1950);
DOT 1 (-2025 1900);
DOT 1 (-2025 2000);
DOT 1 (-2025 2050);
DOT 1 (-2025 2100);
DOT 1 (-2025 2200);
DOT 1 (-2025 2150);
DOT 1 (-2025 2350);
DOT 1 (-2025 2250);
DOT 1 (-2025 2300);
DOT 1 (-2025 2400);
DOT 1 (-2025 2450);
DOT 1 (-2025 2600);
DOT 1 (-2025 2500);
DOT 1 (-2025 2550);
DOT 1 (-2025 2700);
DOT 1 (-2025 2650);
DOT 1 (-2025 2750);
DOT 1 (-2025 2850);
DOT 1 (-2025 2800);
DOT 1 (-2025 2900);
DOT 1 (-2025 2950);
DOT 1 (-2025 3000);
DOT 1 (-2025 3100);
DOT 1 (-2025 3050);
DOT 1 (-2025 3150);
DOT 1 (-2025 3200);
DOT 1 (-2025 3250);
DOT 1 (-2025 3300);
DOT 1 (-2025 3350);
DOT 1 (-2025 3500);
DOT 1 (-2025 3400);
DOT 1 (-2025 3450);
DOT 1 (-2025 3550);
DOT 1 (-2025 3600);
DOT 1 (-2025 3750);
DOT 1 (-2025 3700);
DOT 1 (-2025 3650);
DOT 1 (-2025 3800);
DOT 1 (-2025 3850);
DOT 1 (-2025 3900);
DOT 1 (-2025 4000);
DOT 1 (-2025 3950);
DOT 1 (-2025 4050);
DOT 1 (-2025 4100);
DOT 1 (-500 650);
DOT 1 (-500 700);
DOT 1 (-500 750);
DOT 1 (-500 800);
DOT 1 (-500 850);
DOT 1 (-500 900);
DOT 1 (-500 950);
DOT 1 (-500 1000);
DOT 1 (-500 1050);
DOT 1 (-500 1100);
DOT 1 (-500 1150);
DOT 1 (-500 1200);
DOT 1 (-500 1250);
DOT 1 (-500 1300);
DOT 1 (-500 1350);
DOT 1 (-500 1400);
DOT 1 (-500 1450);
DOT 1 (-500 1500);
DOT 1 (-500 1550);
DOT 1 (-500 1600);
DOT 1 (-500 1650);
DOT 1 (-500 1700);
DOT 1 (-500 1750);
DOT 1 (-500 1800);
DOT 1 (-500 1850);
DOT 1 (-500 1900);
DOT 1 (-500 1950);
DOT 1 (-500 2000);
DOT 1 (-500 2050);
DOT 1 (-500 2100);
DOT 1 (-500 2150);
DOT 1 (-500 2200);
DOT 1 (-500 2250);
DOT 1 (-500 2300);
DOT 1 (-500 2350);
DOT 1 (-500 2450);
DOT 1 (-500 2400);
DOT 1 (-500 2500);
DOT 1 (-500 2550);
DOT 1 (-500 2600);
DOT 1 (-500 2650);
DOT 1 (-500 2700);
DOT 1 (-500 2750);
DOT 1 (-500 2800);
DOT 1 (-500 2850);
DOT 1 (-500 2900);
DOT 1 (-500 2950);
DOT 1 (-500 3050);
DOT 1 (-500 3100);
DOT 1 (-500 3250);
DOT 1 (-500 3200);
DOT 1 (-500 3300);
DOT 1 (-500 3350);
DOT 1 (-500 3400);
DOT 1 (-500 3450);
DOT 1 (-500 3500);
DOT 1 (-500 3550);
DOT 1 (-500 3600);
DOT 1 (-500 3650);
DOT 1 (-500 3700);
DOT 1 (-500 3750);
DOT 1 (-500 3800);
DOT 1 (-500 3850);
DOT 1 (-500 3900);
DOT 1 (-500 3950);
DOT 1 (-500 4000);
DOT 1 (-500 4050);
DOT 1 (-500 4100);
DOT 1 (-500 4150);
DOT 1 (-2025 4150);
DOT 1 (-2025 4250);
DOT 1 (-2025 4200);
DOT 1 (-2025 4400);
DOT 1 (-2025 4300);
DOT 1 (-2025 4350);
DOT 1 (-2025 4450);
DOT 1 (-2025 4500);
DOT 1 (-2025 4550);
DOT 1 (-500 4200);
DOT 1 (-500 4250);
DOT 1 (-500 4300);
DOT 1 (-500 4350);
DOT 1 (-500 4400);
DOT 1 (-500 4500);
DOT 1 (-500 4450);
DOT 1 (-500 4550);
DOT 1 (-500 3150);
DOT 1 (-7625 2600);
DOT 1 (-3950 3325);
DOT 1 (-2425 3675);
DOT 1 (-2425 3825);
DOT 1 (-2425 3875);
DOT 1 (-6100 3500);
DOT 1 (-6100 1150);
DOT 1 (-6100 1100);
DOT 1 (-7625 1300);
DOT 1 (-500 3000);
DOT 1 (-5775 2425);
DOT 1 (-3950 3575);
DOT 1 (-5775 1175);
DOT 1 (-6100 1300);
DOT 1 (-4250 2525);
DOT 1 (-6100 1600);
DOT 1 (-2025 1850);
DOT 1 (-7625 900);
DOT 1 (-5775 3425);
DOT 1 (-6100 3550);
DOT 1 (-5775 4425);
DOT 1 (-5775 4375);
DOT 1 (-5775 4575);
DOT 1 (-5775 4525);
DOT 1 (-6100 1500);
DOT 1 (-6100 1550);
DOT 1 (-6100 2250);
DOT 1 (-6100 2300);
DOT 1 (-6100 3300);
DOT 1 (-5775 4475);
DOT 1 (-4250 4475);
DOT 1 (-3950 4525);
DOT 1 (-5775 2875);
FORCENOTE
BOM_COST=PROC_SOCKET
(-8025 200) 0;
DISPLAY LEFT (-8025 200);
DISPLAY 1.723404 (-8025 200);
PAINT PURPLE (-8025 200);
FORCENOTE
ROOM=CPU1
(-8025 325) 0;
DISPLAY LEFT (-8025 325);
DISPLAY 1.723404 (-8025 325);
PAINT PURPLE (-8025 325);
QUIT
